FILE_TYPE = MACRO_DRAWING;
SET COLOR_WIRE YELLOW;
SET COLOR_PROP MONO;
SET COLOR_DOT WHITE;
SET COLOR_ARC YELLOW;
SET COLOR_BODY GREEN;
SET COLOR_NOTE MONO;
SET PROP_DISPLAY VALUE;
SET PAGE_NUMBER P234;
FORCEADD OFFPAGE..1
(-7650 2825);
FORCEPROP 2 LAST $XR0 191 
J 0
(-7932 2825);
DISPLAY 0.638298 (-7932 2825);
PAINT MONO (-7932 2825);
FORCEPROP 2 LAST $XR1 233 
J 0
(-8052 2825);
DISPLAY 0.638298 (-8052 2825);
PAINT MONO (-8052 2825);
FORCEPROP 2 LAST ROOM PVPP_KLM_VR
J 0
(-8200 2900);
DISPLAY 1.042553 (-8200 2900);
PAINT GREEN (-8200 2900);
DISPLAY INVISIBLE (-8200 2900);
FORCEPROP 2 LAST BOM_COST PVPP_KLM_VR
J 0
(-8475 2900);
DISPLAY 1.042553 (-8475 2900);
PAINT WHITE (-8475 2900);
DISPLAY INVISIBLE (-8475 2900);
FORCEPROP 2 LAST PATH I118
J 0
(-7900 2875);
DISPLAY 1.021277 (-7900 2875);
PAINT ORANGE (-7900 2875);
DISPLAY INVISIBLE (-7900 2875);
FORCEPROP 0 LAST TOLERANCE 1%
J 0
(-7600 2900);
PAINT SKYBLUE (-7600 2900);
DISPLAY INVISIBLE (-7600 2900);
FORCEPROP 1 LAST COMMENT_BODY TRUE
J 0
(-7525 2725);
DISPLAY 0.872340 (-7525 2725);
PAINT PEACH (-7525 2725);
DISPLAY INVISIBLE (-7525 2725);
FORCEPROP 1 LAST OFFPAGE TRUE
J 0
(-7325 2700);
PAINT GREEN (-7325 2700);
DISPLAY INVISIBLE (-7325 2700);
FORCEPROP 2 LAST CDS_LIB mstr_standard
J 0
(-7650 2825);
PAINT MONO (-7650 2825);
DISPLAY INVISIBLE (-7650 2825);
FORCEADD CAP..1
R 2
(-6300 2400);
FORCEPROP 1 LAST VOLTAGE 50V
J 2
(-6350 2400);
DISPLAY 0.617021 (-6350 2400);
PAINT SKYBLUE (-6350 2400);
FORCEPROP 1 LAST PACK_TYPE 0402LF
J 2
(-6350 2200);
DISPLAY 0.617021 (-6350 2200);
PAINT SKYBLUE (-6350 2200);
FORCEPROP 1 LAST TOLERANCE 10%
J 2
(-6350 2350);
DISPLAY 0.617021 (-6350 2350);
PAINT SKYBLUE (-6350 2350);
FORCEPROP 1 LAST VALUE 1000PF
J 2
(-6350 2450);
DISPLAY 0.617021 (-6350 2450);
PAINT SKYBLUE (-6350 2450);
FORCEPROP 1 LAST PART_NUMBER A36096-046
J 2
(-6325 2250);
DISPLAY 0.617021 (-6325 2250);
PAINT BLUE (-6325 2250);
FORCEPROP 1 LAST LOCATION C4B5
J 2
(-6350 2500);
DISPLAY 0.617021 (-6350 2500);
PAINT AQUA (-6350 2500);
FORCEPROP 1 LAST MATERIAL EMPTY
J 2
(-6350 2300);
DISPLAY 0.617021 (-6350 2300);
PAINT RED (-6350 2300);
FORCEPROP 1 LASTPIN (-6300 2300) $PN 2
J 2
(-6310 2280);
DISPLAY 0.617021 (-6310 2280);
PAINT WHITE (-6310 2280);
FORCEPROP 1 LASTPIN (-6300 2500) $PN 1
J 2
(-6310 2480);
DISPLAY 0.617021 (-6310 2480);
PAINT WHITE (-6310 2480);
FORCEPROP 2 LAST ROOM PVPP_KLM_VR
J 2
(-6300 2400);
PAINT GREEN (-6300 2400);
DISPLAY INVISIBLE (-6300 2400);
FORCEPROP 2 LAST BOM_COST PVPP_KLM_VR
J 2
(-6300 2400);
PAINT WHITE (-6300 2400);
DISPLAY INVISIBLE (-6300 2400);
FORCEPROP 2 LAST CDS_LIB mstr_discrete
J 2
(-6300 2400);
PAINT MONO (-6300 2400);
DISPLAY INVISIBLE (-6300 2400);
FORCEPROP 2 LAST CDS_LOCATION C4B5
J 2
(-6350 2500);
DISPLAY 0.617021 (-6350 2500);
PAINT AQUA (-6350 2500);
DISPLAY INVISIBLE (-6350 2500);
FORCEPROP 1 LAST PATH I129
J 2
(-6350 2550);
DISPLAY 0.978723 (-6350 2550);
PAINT WHITE (-6350 2550);
DISPLAY INVISIBLE (-6350 2550);
FORCEPROP 2 LAST $SEC 1
J 2
(-6350 2600);
DISPLAY 0.680851 (-6350 2600);
PAINT MONO (-6350 2600);
DISPLAY INVISIBLE (-6350 2600);
FORCEPROP 2 LAST CDS_SEC 1
J 2
(-6350 2600);
DISPLAY 1.042553 (-6350 2600);
PAINT ORANGE (-6350 2600);
DISPLAY INVISIBLE (-6350 2600);
FORCEPROP 0 LAST REUSE_ID 1
J 2
(-6350 2600);
DISPLAY 1.042553 (-6350 2600);
PAINT ORANGE (-6350 2600);
DISPLAY INVISIBLE (-6350 2600);
FORCEPROP 0 LAST FIN VR_1P2
J 2
(-6350 2700);
PAINT ORANGE (-6350 2700);
DISPLAY INVISIBLE (-6350 2700);
FORCEADD CAP..1
(-7275 4150);
FORCEPROP 1 LASTPIN (-7275 4050) $PN 2
J 0
(-7265 4030);
DISPLAY 0.617021 (-7265 4030);
PAINT WHITE (-7265 4030);
FORCEPROP 1 LAST MATERIAL X6S
J 0
(-7225 4050);
DISPLAY 0.617021 (-7225 4050);
PAINT SKYBLUE (-7225 4050);
FORCEPROP 1 LAST PACK_TYPE 1210
J 0
(-7225 3950);
DISPLAY 0.617021 (-7225 3950);
PAINT SKYBLUE (-7225 3950);
FORCEPROP 1 LAST PART_NUMBER D38464-007
J 0
(-7225 4000);
DISPLAY 0.617021 (-7225 4000);
PAINT BLUE (-7225 4000);
FORCEPROP 1 LASTPIN (-7275 4250) $PN 1
J 0
(-7265 4230);
DISPLAY 0.617021 (-7265 4230);
PAINT WHITE (-7265 4230);
FORCEPROP 1 LAST VOLTAGE 16V
J 0
(-7225 4150);
DISPLAY 0.617021 (-7225 4150);
PAINT SKYBLUE (-7225 4150);
FORCEPROP 1 LAST TOLERANCE 20%
J 0
(-7225 4100);
DISPLAY 0.617021 (-7225 4100);
PAINT SKYBLUE (-7225 4100);
FORCEPROP 1 LAST VALUE 47UF
J 0
(-7225 4200);
DISPLAY 0.617021 (-7225 4200);
PAINT SKYBLUE (-7225 4200);
FORCEPROP 1 LAST LOCATION C4B1
J 0
(-7225 4250);
DISPLAY 0.617021 (-7225 4250);
PAINT AQUA (-7225 4250);
FORCEPROP 2 LAST ROOM PVPP_KLM_VR
J 0
(-7275 4150);
PAINT GREEN (-7275 4150);
DISPLAY INVISIBLE (-7275 4150);
FORCEPROP 2 LAST BOM_COST PVPP_KLM_VR
J 0
(-7275 4150);
PAINT WHITE (-7275 4150);
DISPLAY INVISIBLE (-7275 4150);
FORCEPROP 2 LAST CDS_LIB mstr_discrete
J 0
(-7275 4150);
PAINT MONO (-7275 4150);
DISPLAY INVISIBLE (-7275 4150);
FORCEPROP 2 LAST CDS_LOCATION C4B1
J 0
(-7225 4250);
DISPLAY 0.617021 (-7225 4250);
PAINT AQUA (-7225 4250);
DISPLAY INVISIBLE (-7225 4250);
FORCEPROP 1 LAST PATH I130
J 0
(-7225 4300);
DISPLAY 0.978723 (-7225 4300);
PAINT WHITE (-7225 4300);
DISPLAY INVISIBLE (-7225 4300);
FORCEPROP 2 LAST $SEC 1
J 0
(-7225 4350);
DISPLAY 0.680851 (-7225 4350);
PAINT MONO (-7225 4350);
DISPLAY INVISIBLE (-7225 4350);
FORCEPROP 2 LAST CDS_SEC 1
J 0
(-7225 4350);
DISPLAY 1.042553 (-7225 4350);
PAINT ORANGE (-7225 4350);
DISPLAY INVISIBLE (-7225 4350);
FORCEADD GND..1
(-7275 3900);
FORCEPROP 3 LASTPIN (-7275 3950) SIG_NAME GND\g
J 0
(-7265 3960);
DISPLAY 0.659574 (-7265 3960);
PAINT MONO (-7265 3960);
DISPLAY INVISIBLE (-7265 3960);
FORCEPROP 2 LAST BOM_COST PVPP_KLM_VR
J 0
(-8125 3975);
DISPLAY 1.042553 (-8125 3975);
PAINT WHITE (-8125 3975);
DISPLAY INVISIBLE (-8125 3975);
FORCEPROP 2 LAST ROOM PVPP_KLM_VR
J 0
(-7850 3975);
DISPLAY 1.042553 (-7850 3975);
PAINT GREEN (-7850 3975);
DISPLAY INVISIBLE (-7850 3975);
FORCEPROP 1 LAST BODY_TYPE PLUMBING
J 0
(-7320 3857);
DISPLAY 0.340426 (-7320 3857);
PAINT GREEN (-7320 3857);
DISPLAY INVISIBLE (-7320 3857);
FORCEPROP 1 LAST PATH I131
J 0
(-7200 3900);
DISPLAY 0.872340 (-7200 3900);
PAINT AQUA (-7200 3900);
DISPLAY INVISIBLE (-7200 3900);
FORCEPROP 1 LAST VOLTAGE 0
J 0
(-7275 3900);
PAINT SKYBLUE (-7275 3900);
DISPLAY INVISIBLE (-7275 3900);
FORCEPROP 2 LAST CDS_LIB mstr_symbols
J 0
(-7275 3900);
PAINT MONO (-7275 3900);
DISPLAY INVISIBLE (-7275 3900);
FORCEPROP 1 LAST SIZE 1B
J 0
(-7200 3850);
DISPLAY 0.872340 (-7200 3850);
PAINT GREEN (-7200 3850);
DISPLAY INVISIBLE (-7200 3850);
FORCEPROP 1 LAST HDL_POWER GND
J 0
(-7275 4050);
DISPLAY 0.872340 (-7275 4050);
PAINT GREEN (-7275 4050);
DISPLAY INVISIBLE (-7275 4050);
FORCEADD GND..1
(-3875 475);
FORCEPROP 3 LASTPIN (-3875 525) SIG_NAME GND\g
J 0
(-3865 535);
DISPLAY 0.659574 (-3865 535);
PAINT MONO (-3865 535);
DISPLAY INVISIBLE (-3865 535);
FORCEPROP 2 LAST BOM_COST PVPP_KLM_VR
J 0
(-4775 625);
DISPLAY 1.042553 (-4775 625);
PAINT WHITE (-4775 625);
DISPLAY INVISIBLE (-4775 625);
FORCEPROP 2 LAST ROOM PVPP_KLM_VR
J 0
(-4525 625);
PAINT GREEN (-4525 625);
DISPLAY INVISIBLE (-4525 625);
FORCEPROP 1 LAST PATH I138
J 0
(-3800 475);
DISPLAY 0.872340 (-3800 475);
PAINT AQUA (-3800 475);
DISPLAY INVISIBLE (-3800 475);
FORCEPROP 1 LAST BODY_TYPE PLUMBING
J 0
(-3920 432);
DISPLAY 0.340426 (-3920 432);
PAINT GREEN (-3920 432);
DISPLAY INVISIBLE (-3920 432);
FORCEPROP 1 LAST SIZE 1B
J 0
(-3800 500);
DISPLAY 0.893617 (-3800 500);
PAINT GREEN (-3800 500);
DISPLAY INVISIBLE (-3800 500);
FORCEPROP 1 LAST VOLTAGE 0
J 0
(-3875 550);
PAINT SKYBLUE (-3875 550);
DISPLAY INVISIBLE (-3875 550);
FORCEPROP 2 LAST CDS_LIB mstr_symbols
J 0
(-3875 550);
PAINT MONO (-3875 550);
DISPLAY INVISIBLE (-3875 550);
FORCEPROP 1 LAST HDL_POWER GND
J 0
(-3875 700);
DISPLAY 0.893617 (-3875 700);
PAINT GREEN (-3875 700);
DISPLAY INVISIBLE (-3875 700);
FORCEADD CAP..1
(-3875 725);
FORCEPROP 1 LASTPIN (-3875 825) $PN 1
J 0
(-3865 805);
DISPLAY 0.617021 (-3865 805);
PAINT WHITE (-3865 805);
FORCEPROP 1 LASTPIN (-3875 625) $PN 2
J 0
(-3865 605);
DISPLAY 0.617021 (-3865 605);
PAINT WHITE (-3865 605);
FORCEPROP 1 LAST TOLERANCE 10%
J 0
(-3825 675);
DISPLAY 0.617021 (-3825 675);
PAINT SKYBLUE (-3825 675);
FORCEPROP 1 LAST LOCATION C4B8
J 0
(-3825 825);
DISPLAY 0.617021 (-3825 825);
PAINT AQUA (-3825 825);
FORCEPROP 1 LAST VALUE 1000PF
J 0
(-3825 775);
DISPLAY 0.617021 (-3825 775);
PAINT SKYBLUE (-3825 775);
FORCEPROP 1 LAST MATERIAL X7R
J 0
(-3825 625);
DISPLAY 0.617021 (-3825 625);
PAINT SKYBLUE (-3825 625);
FORCEPROP 1 LAST VOLTAGE 50V
J 0
(-3825 725);
DISPLAY 0.617021 (-3825 725);
PAINT SKYBLUE (-3825 725);
FORCEPROP 1 LAST PACK_TYPE 0402LF
J 0
(-3825 575);
DISPLAY 0.617021 (-3825 575);
PAINT SKYBLUE (-3825 575);
FORCEPROP 1 LAST PART_NUMBER A36096-046
J 0
(-3825 525);
DISPLAY 0.617021 (-3825 525);
PAINT BLUE (-3825 525);
FORCEPROP 2 LAST ROOM PVPP_KLM_VR
J 0
(-3875 725);
PAINT GREEN (-3875 725);
DISPLAY INVISIBLE (-3875 725);
FORCEPROP 2 LAST CDS_LIB mstr_discrete
J 2
(-3875 725);
PAINT MONO (-3875 725);
DISPLAY INVISIBLE (-3875 725);
FORCEPROP 2 LAST BOM_COST PVPP_KLM_VR
J 0
(-3875 725);
PAINT WHITE (-3875 725);
DISPLAY INVISIBLE (-3875 725);
FORCEPROP 2 LAST REUSE_ID 17
J 0
(-3825 925);
DISPLAY 1.042553 (-3825 925);
PAINT ORANGE (-3825 925);
DISPLAY INVISIBLE (-3825 925);
FORCEPROP 2 LAST CDS_SEC 1
J 2
(-3825 925);
DISPLAY 1.042553 (-3825 925);
PAINT ORANGE (-3825 925);
DISPLAY INVISIBLE (-3825 925);
FORCEPROP 2 LAST $SEC 1
J 2
(-3825 925);
DISPLAY 0.680851 (-3825 925);
PAINT MONO (-3825 925);
DISPLAY INVISIBLE (-3825 925);
FORCEPROP 1 LAST PATH I139
J 0
(-3825 875);
DISPLAY 0.978723 (-3825 875);
PAINT WHITE (-3825 875);
DISPLAY INVISIBLE (-3825 875);
FORCEPROP 2 LAST CDS_LOCATION C4B8
J 0
(-3825 825);
DISPLAY 0.617021 (-3825 825);
PAINT AQUA (-3825 825);
DISPLAY INVISIBLE (-3825 825);
FORCEADD RES..2
R 2
(-4750 1650);
FORCEPROP 1 LAST PACK_TYPE 0402
J 2
(-4790 1475);
DISPLAY 0.617021 (-4790 1475);
PAINT SKYBLUE (-4790 1475);
FORCEPROP 1 LAST PART_NUMBER G21796-242
J 2
(-4790 1525);
DISPLAY 0.617021 (-4790 1525);
PAINT BLUE (-4790 1525);
FORCEPROP 1 LAST WATTAGE 1/16W
J 2
(-4790 1625);
DISPLAY 0.617021 (-4790 1625);
PAINT SKYBLUE (-4790 1625);
FORCEPROP 1 LAST MATERIAL CHIP
J 2
(-4790 1575);
DISPLAY 0.617021 (-4790 1575);
PAINT SKYBLUE (-4790 1575);
FORCEPROP 1 LAST TOLERANCE 1.0%
J 2
(-4795 1675);
DISPLAY 0.617021 (-4795 1675);
PAINT SKYBLUE (-4795 1675);
FORCEPROP 1 LAST VALUE 7.87K
J 2
(-4795 1725);
DISPLAY 0.617021 (-4795 1725);
PAINT SKYBLUE (-4795 1725);
FORCEPROP 1 LAST LOCATION R4B6
J 2
(-4795 1775);
DISPLAY 0.617021 (-4795 1775);
PAINT AQUA (-4795 1775);
FORCEPROP 1 LASTPIN (-4750 1550) $PN 2
J 2
(-4755 1560);
DISPLAY 0.617021 (-4755 1560);
PAINT WHITE (-4755 1560);
FORCEPROP 1 LASTPIN (-4750 1750) $PN 1
J 2
(-4755 1712);
DISPLAY 0.617021 (-4755 1712);
PAINT WHITE (-4755 1712);
FORCEPROP 2 LAST CDS_LIB mstr_discrete
J 2
(-4750 1650);
PAINT MONO (-4750 1650);
DISPLAY INVISIBLE (-4750 1650);
FORCEPROP 2 LAST BOM_COST PVPP_KLM_VR
J 2
(-4750 1650);
PAINT WHITE (-4750 1650);
DISPLAY INVISIBLE (-4750 1650);
FORCEPROP 2 LAST ROOM PVPP_KLM_VR
J 2
(-4750 1650);
PAINT GREEN (-4750 1650);
DISPLAY INVISIBLE (-4750 1650);
FORCEPROP 2 LAST CDS_LOCATION R4B6
J 2
(-4795 1775);
DISPLAY 0.617021 (-4795 1775);
PAINT AQUA (-4795 1775);
DISPLAY INVISIBLE (-4795 1775);
FORCEPROP 2 LAST SEC_TYPE 0402
J 0
(-4800 1875);
DISPLAY 1.021277 (-4800 1875);
PAINT ORANGE (-4800 1875);
DISPLAY INVISIBLE (-4800 1875);
FORCEPROP 2 LAST SEC 1
J 0
(-4800 1875);
DISPLAY 0.680851 (-4800 1875);
PAINT MONO (-4800 1875);
DISPLAY INVISIBLE (-4800 1875);
FORCEPROP 1 LAST PATH I140
J 2
(-4800 1825);
DISPLAY 0.978723 (-4800 1825);
PAINT WHITE (-4800 1825);
DISPLAY INVISIBLE (-4800 1825);
FORCEADD P3V3_STBY..1
(-4225 1525);
FORCEPROP 3 LASTPIN (-4225 1475) SIG_NAME P3V3_STBY\g
J 0
(-4215 1485);
DISPLAY 0.659574 (-4215 1485);
PAINT MONO (-4215 1485);
DISPLAY INVISIBLE (-4215 1485);
FORCEPROP 1 LAST HDL_POWER P3V3_STBY
J 0
(-4525 1400);
DISPLAY 0.872340 (-4525 1400);
PAINT ORANGE (-4525 1400);
DISPLAY INVISIBLE (-4525 1400);
FORCEPROP 1 LAST BODY_TYPE PLUMBING
J 0
(-4270 1482);
DISPLAY 0.340426 (-4270 1482);
PAINT GREEN (-4270 1482);
DISPLAY INVISIBLE (-4270 1482);
FORCEPROP 1 LAST PATH I142
J 0
(-4180 1527);
DISPLAY 0.340426 (-4180 1527);
PAINT GREEN (-4180 1527);
DISPLAY INVISIBLE (-4180 1527);
FORCEPROP 2 LAST CDS_LIB mstr_symbols
J 0
(-4225 1525);
PAINT MONO (-4225 1525);
DISPLAY INVISIBLE (-4225 1525);
FORCEPROP 1 LAST SIZE 1B
J 0
(-4180 1547);
DISPLAY 0.340426 (-4180 1547);
PAINT GREEN (-4180 1547);
DISPLAY INVISIBLE (-4180 1547);
FORCEPROP 1 LAST VOLTAGE +3.3V
J 0
(-4025 1675);
DISPLAY 1.021277 (-4025 1675);
PAINT SKYBLUE (-4025 1675);
DISPLAY INVISIBLE (-4025 1675);
FORCEADD RES..2
(-4225 1250);
FORCEPROP 1 LASTPIN (-4225 1150) $PN 2
J 0
(-4220 1160);
DISPLAY 0.617021 (-4220 1160);
PAINT WHITE (-4220 1160);
FORCEPROP 1 LAST TOLERANCE 1%
J 0
(-4180 1275);
DISPLAY 0.617021 (-4180 1275);
PAINT SKYBLUE (-4180 1275);
FORCEPROP 1 LASTPIN (-4225 1350) $PN 1
J 0
(-4220 1312);
DISPLAY 0.617021 (-4220 1312);
PAINT WHITE (-4220 1312);
FORCEPROP 1 LAST WATTAGE 1/16W
J 0
(-4185 1225);
DISPLAY 0.617021 (-4185 1225);
PAINT SKYBLUE (-4185 1225);
FORCEPROP 1 LAST MATERIAL CHIP
J 0
(-4185 1175);
DISPLAY 0.617021 (-4185 1175);
PAINT SKYBLUE (-4185 1175);
FORCEPROP 1 LAST PACK_TYPE 0402
J 0
(-4185 1075);
DISPLAY 0.617021 (-4185 1075);
PAINT SKYBLUE (-4185 1075);
FORCEPROP 1 LAST VALUE 1.00K
J 0
(-4180 1325);
DISPLAY 0.617021 (-4180 1325);
PAINT SKYBLUE (-4180 1325);
FORCEPROP 1 LAST PART_NUMBER G21796-026
J 0
(-4185 1125);
DISPLAY 0.617021 (-4185 1125);
PAINT BLUE (-4185 1125);
FORCEPROP 1 LAST LOCATION R4B10
J 0
(-4180 1375);
DISPLAY 0.617021 (-4180 1375);
PAINT AQUA (-4180 1375);
FORCEPROP 2 LAST CDS_LIB mstr_discrete
J 0
(-4225 1250);
PAINT MONO (-4225 1250);
DISPLAY INVISIBLE (-4225 1250);
FORCEPROP 2 LAST REUSE_ID 21
J 0
(-4175 1475);
DISPLAY 1.042553 (-4175 1475);
PAINT ORANGE (-4175 1475);
DISPLAY INVISIBLE (-4175 1475);
FORCEPROP 2 LAST BOM_COST PVPP_KLM_VR
J 0
(-4165 1440);
DISPLAY 1.042553 (-4165 1440);
PAINT WHITE (-4165 1440);
DISPLAY INVISIBLE (-4165 1440);
FORCEPROP 2 LAST SEC_TYPE 0402
J 0
(-4175 1475);
DISPLAY 1.042553 (-4175 1475);
PAINT ORANGE (-4175 1475);
DISPLAY INVISIBLE (-4175 1475);
FORCEPROP 2 LAST SEC 1
J 0
(-4175 1475);
DISPLAY 0.680851 (-4175 1475);
PAINT MONO (-4175 1475);
DISPLAY INVISIBLE (-4175 1475);
FORCEPROP 2 LAST CDS_LOCATION R4B10
J 0
(-4180 1375);
DISPLAY 0.617021 (-4180 1375);
PAINT AQUA (-4180 1375);
DISPLAY INVISIBLE (-4180 1375);
FORCEPROP 1 LAST PATH I143
J 0
(-4175 1425);
DISPLAY 0.978723 (-4175 1425);
PAINT WHITE (-4175 1425);
DISPLAY INVISIBLE (-4175 1425);
FORCEPROP 2 LAST ROOM PVPP_KLM_VR
J 0
(-4165 1415);
PAINT GREEN (-4165 1415);
DISPLAY INVISIBLE (-4165 1415);
FORCEADD CAP..1
(-5600 2400);
FORCEPROP 1 LAST MATERIAL X6S
J 0
(-5550 2200);
DISPLAY 0.617021 (-5550 2200);
PAINT SKYBLUE (-5550 2200);
FORCEPROP 1 LASTPIN (-5600 2300) $PN 2
J 0
(-5590 2280);
DISPLAY 0.617021 (-5590 2280);
PAINT ORANGE (-5590 2280);
FORCEPROP 1 LAST PACK_TYPE 0603
J 0
(-5550 2300);
DISPLAY 0.617021 (-5550 2300);
PAINT SKYBLUE (-5550 2300);
FORCEPROP 1 LASTPIN (-5600 2500) $PN 1
J 0
(-5590 2480);
DISPLAY 0.617021 (-5590 2480);
PAINT ORANGE (-5590 2480);
FORCEPROP 1 LAST VOLTAGE 6.3V
J 0
(-5525 2400);
DISPLAY 0.617021 (-5525 2400);
PAINT SKYBLUE (-5525 2400);
FORCEPROP 1 LAST TOLERANCE 10%
J 0
(-5525 2350);
DISPLAY 0.617021 (-5525 2350);
PAINT SKYBLUE (-5525 2350);
FORCEPROP 1 LAST LOCATION C6L12
J 0
(-5550 2500);
DISPLAY 0.617021 (-5550 2500);
PAINT AQUA (-5550 2500);
FORCEPROP 1 LAST VALUE 4.7UF
J 0
(-5550 2450);
DISPLAY 0.617021 (-5550 2450);
PAINT SKYBLUE (-5550 2450);
FORCEPROP 1 LAST PART_NUMBER E15431-003
J 0
(-5575 2250);
DISPLAY 0.617021 (-5575 2250);
PAINT BLUE (-5575 2250);
FORCEPROP 2 LAST CDS_LIB mstr_discrete
J 0
(-5600 2400);
PAINT MONO (-5600 2400);
DISPLAY INVISIBLE (-5600 2400);
FORCEPROP 2 LAST ROOM PVPP_KLM_VR
J 0
(-5550 2525);
PAINT GREEN (-5550 2525);
DISPLAY INVISIBLE (-5550 2525);
FORCEPROP 1 LAST PATH I144
J 0
(-5550 2550);
DISPLAY 0.978723 (-5550 2550);
PAINT WHITE (-5550 2550);
DISPLAY INVISIBLE (-5550 2550);
FORCEPROP 2 LAST BOM_COST PVPP_KLM_VR
J 0
(-5550 2550);
DISPLAY 1.042553 (-5550 2550);
PAINT WHITE (-5550 2550);
DISPLAY INVISIBLE (-5550 2550);
FORCEPROP 2 LAST SEC_TYPE 0603
J 0
(-5550 2600);
DISPLAY 1.021277 (-5550 2600);
PAINT ORANGE (-5550 2600);
DISPLAY INVISIBLE (-5550 2600);
FORCEPROP 2 LAST REUSE_ID 26
J 0
(-5550 2600);
DISPLAY 1.042553 (-5550 2600);
PAINT ORANGE (-5550 2600);
DISPLAY INVISIBLE (-5550 2600);
FORCEPROP 2 LAST SEC 1
J 0
(-5550 2600);
PAINT MONO (-5550 2600);
DISPLAY INVISIBLE (-5550 2600);
FORCEADD CAP..1
(-5075 2175);
FORCEPROP 1 LAST MATERIAL X7R
J 0
(-5025 1975);
DISPLAY 0.617021 (-5025 1975);
PAINT SKYBLUE (-5025 1975);
FORCEPROP 1 LAST PART_NUMBER A36096-129
J 0
(-5050 2025);
DISPLAY 0.617021 (-5050 2025);
PAINT BLUE (-5050 2025);
FORCEPROP 1 LASTPIN (-5075 2275) $PN 1
J 0
(-5065 2255);
DISPLAY 0.617021 (-5065 2255);
PAINT ORANGE (-5065 2255);
FORCEPROP 1 LASTPIN (-5075 2075) $PN 2
J 0
(-5065 2055);
DISPLAY 0.617021 (-5065 2055);
PAINT ORANGE (-5065 2055);
FORCEPROP 1 LAST LOCATION C4B6
J 0
(-5025 2275);
DISPLAY 0.617021 (-5025 2275);
PAINT AQUA (-5025 2275);
FORCEPROP 1 LAST TOLERANCE 10%
J 0
(-5000 2125);
DISPLAY 0.617021 (-5000 2125);
PAINT SKYBLUE (-5000 2125);
FORCEPROP 1 LAST PACK_TYPE 0402
J 0
(-5025 2075);
DISPLAY 0.617021 (-5025 2075);
PAINT SKYBLUE (-5025 2075);
FORCEPROP 1 LAST VOLTAGE 16V
J 0
(-5000 2175);
DISPLAY 0.617021 (-5000 2175);
PAINT SKYBLUE (-5000 2175);
FORCEPROP 1 LAST VALUE 0.027UF
J 0
(-5025 2225);
DISPLAY 0.617021 (-5025 2225);
PAINT SKYBLUE (-5025 2225);
FORCEPROP 2 LAST CDS_LIB mstr_discrete
J 0
(-5075 2175);
PAINT MONO (-5075 2175);
DISPLAY INVISIBLE (-5075 2175);
FORCEPROP 2 LAST CDS_LOCATION C4B6
J 0
(-5025 2275);
DISPLAY 0.617021 (-5025 2275);
PAINT AQUA (-5025 2275);
DISPLAY INVISIBLE (-5025 2275);
FORCEPROP 2 LAST ROOM PVPP_KLM_VR
J 0
(-5025 2300);
PAINT GREEN (-5025 2300);
DISPLAY INVISIBLE (-5025 2300);
FORCEPROP 2 LAST SEC_TYPE 0402
J 0
(-5025 2375);
DISPLAY 1.021277 (-5025 2375);
PAINT ORANGE (-5025 2375);
DISPLAY INVISIBLE (-5025 2375);
FORCEPROP 2 LAST BOM_COST PVPP_KLM_VR
J 0
(-5025 2325);
DISPLAY 1.042553 (-5025 2325);
PAINT WHITE (-5025 2325);
DISPLAY INVISIBLE (-5025 2325);
FORCEPROP 2 LAST REUSE_ID 26
J 0
(-5025 2375);
DISPLAY 1.042553 (-5025 2375);
PAINT ORANGE (-5025 2375);
DISPLAY INVISIBLE (-5025 2375);
FORCEPROP 0 LAST SEC 1
J 0
(-5025 2325);
DISPLAY 0.680851 (-5025 2325);
PAINT MONO (-5025 2325);
DISPLAY INVISIBLE (-5025 2325);
FORCEPROP 1 LAST PATH I146
J 0
(-5025 2325);
DISPLAY 0.978723 (-5025 2325);
PAINT WHITE (-5025 2325);
DISPLAY INVISIBLE (-5025 2325);
FORCEADD GND..1
(-4950 3825);
FORCEPROP 3 LASTPIN (-4950 3875) SIG_NAME GND\g
J 0
(-4940 3885);
DISPLAY 0.659574 (-4940 3885);
PAINT MONO (-4940 3885);
DISPLAY INVISIBLE (-4940 3885);
FORCEPROP 2 LAST BOM_COST PVPP_KLM_VR
J 0
(-5800 3900);
DISPLAY 1.042553 (-5800 3900);
PAINT WHITE (-5800 3900);
DISPLAY INVISIBLE (-5800 3900);
FORCEPROP 2 LAST ROOM PVPP_KLM_VR
J 0
(-5525 3900);
DISPLAY 1.042553 (-5525 3900);
PAINT GREEN (-5525 3900);
DISPLAY INVISIBLE (-5525 3900);
FORCEPROP 1 LAST SIZE 1B
J 0
(-4875 3775);
DISPLAY 0.872340 (-4875 3775);
PAINT GREEN (-4875 3775);
DISPLAY INVISIBLE (-4875 3775);
FORCEPROP 1 LAST BODY_TYPE PLUMBING
J 0
(-4995 3782);
DISPLAY 0.340426 (-4995 3782);
PAINT GREEN (-4995 3782);
DISPLAY INVISIBLE (-4995 3782);
FORCEPROP 1 LAST PATH I151
J 0
(-4875 3825);
DISPLAY 0.872340 (-4875 3825);
PAINT AQUA (-4875 3825);
DISPLAY INVISIBLE (-4875 3825);
FORCEPROP 2 LAST CDS_LIB mstr_symbols
J 0
(-4950 3825);
PAINT MONO (-4950 3825);
DISPLAY INVISIBLE (-4950 3825);
FORCEPROP 1 LAST VOLTAGE 0
J 0
(-4950 3825);
PAINT SKYBLUE (-4950 3825);
DISPLAY INVISIBLE (-4950 3825);
FORCEPROP 1 LAST HDL_POWER GND
J 0
(-4950 3975);
DISPLAY 0.872340 (-4950 3975);
PAINT GREEN (-4950 3975);
DISPLAY INVISIBLE (-4950 3975);
FORCEADD CAP..1
(-4950 4150);
FORCEPROP 1 LASTPIN (-4950 4050) $PN 2
J 0
(-4940 4030);
DISPLAY 0.617021 (-4940 4030);
PAINT WHITE (-4940 4030);
FORCEPROP 1 LAST PART_NUMBER D97712-011
J 0
(-4900 4000);
DISPLAY 0.617021 (-4900 4000);
PAINT BLUE (-4900 4000);
FORCEPROP 1 LAST PACK_TYPE 0402
J 0
(-4900 3950);
DISPLAY 0.617021 (-4900 3950);
PAINT SKYBLUE (-4900 3950);
FORCEPROP 1 LAST MATERIAL X6S
J 0
(-4900 4050);
DISPLAY 0.617021 (-4900 4050);
PAINT SKYBLUE (-4900 4050);
FORCEPROP 1 LASTPIN (-4950 4250) $PN 1
J 0
(-4940 4230);
DISPLAY 0.617021 (-4940 4230);
PAINT WHITE (-4940 4230);
FORCEPROP 1 LAST VOLTAGE 16V
J 0
(-4900 4150);
DISPLAY 0.617021 (-4900 4150);
PAINT SKYBLUE (-4900 4150);
FORCEPROP 1 LAST TOLERANCE 10%
J 0
(-4900 4100);
DISPLAY 0.617021 (-4900 4100);
PAINT SKYBLUE (-4900 4100);
FORCEPROP 1 LAST VALUE 1.0UF
J 0
(-4900 4200);
DISPLAY 0.617021 (-4900 4200);
PAINT SKYBLUE (-4900 4200);
FORCEPROP 1 LAST LOCATION C6L11
J 0
(-4900 4250);
DISPLAY 0.617021 (-4900 4250);
PAINT AQUA (-4900 4250);
FORCEPROP 2 LAST CDS_LIB mstr_discrete
J 0
(-4950 4150);
PAINT MONO (-4950 4150);
DISPLAY INVISIBLE (-4950 4150);
FORCEPROP 2 LAST BOM_COST PVPP_KLM_VR
J 0
(-4950 4150);
PAINT WHITE (-4950 4150);
DISPLAY INVISIBLE (-4950 4150);
FORCEPROP 2 LAST ROOM PVPP_KLM_VR
J 0
(-4950 4150);
PAINT GREEN (-4950 4150);
DISPLAY INVISIBLE (-4950 4150);
FORCEPROP 2 LAST CDS_LOCATION C6L11
J 0
(-4900 4250);
DISPLAY 0.617021 (-4900 4250);
PAINT AQUA (-4900 4250);
DISPLAY INVISIBLE (-4900 4250);
FORCEPROP 1 LAST PATH I152
J 0
(-4900 4300);
DISPLAY 0.978723 (-4900 4300);
PAINT WHITE (-4900 4300);
DISPLAY INVISIBLE (-4900 4300);
FORCEPROP 0 LAST REUSE_ID 1
J 0
(-4900 4350);
DISPLAY 1.042553 (-4900 4350);
PAINT ORANGE (-4900 4350);
DISPLAY INVISIBLE (-4900 4350);
FORCEPROP 2 LAST CDS_SEC 1
J 0
(-4900 4350);
DISPLAY 1.042553 (-4900 4350);
PAINT ORANGE (-4900 4350);
DISPLAY INVISIBLE (-4900 4350);
FORCEPROP 2 LAST $SEC 1
J 0
(-4900 4350);
DISPLAY 0.680851 (-4900 4350);
PAINT MONO (-4900 4350);
DISPLAY INVISIBLE (-4900 4350);
FORCEPROP 0 LAST FIN VR_1P2
J 0
(-4900 4450);
PAINT ORANGE (-4900 4450);
DISPLAY INVISIBLE (-4900 4450);
FORCEADD P12V_STBY..1
(-7825 4500);
FORCEPROP 3 LASTPIN (-7825 4450) SIG_NAME P12V_STBY\g
J 0
(-7815 4460);
DISPLAY 0.659574 (-7815 4460);
PAINT MONO (-7815 4460);
DISPLAY INVISIBLE (-7815 4460);
FORCEPROP 1 LAST HDL_POWER P12V_STBY
J 0
(-8125 4375);
DISPLAY 0.872340 (-8125 4375);
PAINT ORANGE (-8125 4375);
DISPLAY INVISIBLE (-8125 4375);
FORCEPROP 1 LAST PATH I153
J 0
(-7780 4502);
DISPLAY 0.340426 (-7780 4502);
PAINT GREEN (-7780 4502);
DISPLAY INVISIBLE (-7780 4502);
FORCEPROP 1 LAST BODY_TYPE PLUMBING
J 0
(-7870 4457);
DISPLAY 0.340426 (-7870 4457);
PAINT GREEN (-7870 4457);
DISPLAY INVISIBLE (-7870 4457);
FORCEPROP 1 LAST SIZE 1B
J 0
(-7780 4522);
DISPLAY 0.340426 (-7780 4522);
PAINT GREEN (-7780 4522);
DISPLAY INVISIBLE (-7780 4522);
FORCEPROP 2 LAST CDS_LIB mstr_symbols
J 0
(-7825 4500);
PAINT ORANGE (-7825 4500);
DISPLAY INVISIBLE (-7825 4500);
FORCEPROP 1 LAST VOLTAGE 12.0V
J 0
(-7870 4457);
DISPLAY 0.340426 (-7870 4457);
PAINT SKYBLUE (-7870 4457);
DISPLAY INVISIBLE (-7870 4457);
FORCEADD FERRITE..1
(-7500 4300);
FORCEPROP 1 LASTPIN (-7600 4300) $PN 1
J 2
(-7565 4310);
DISPLAY 0.617021 (-7565 4310);
PAINT WHITE (-7565 4310);
FORCEPROP 1 LAST VALUE 22
J 2
(-7520 4200);
DISPLAY 0.617021 (-7520 4200);
PAINT SKYBLUE (-7520 4200);
FORCEPROP 1 LAST MATERIAL FB
J 0
(-7495 4200);
DISPLAY 0.617021 (-7495 4200);
PAINT SKYBLUE (-7495 4200);
FORCEPROP 1 LAST LOCATION FB4A1
J 0
(-7595 4355);
DISPLAY 0.617021 (-7595 4355);
PAINT AQUA (-7595 4355);
FORCEPROP 1 LAST PART_NUMBER 656554-051
J 0
(-7595 4415);
DISPLAY 0.617021 (-7595 4415);
PAINT BLUE (-7595 4415);
FORCEPROP 1 LASTPIN (-7400 4300) $PN 2
J 0
(-7420 4310);
DISPLAY 0.617021 (-7420 4310);
PAINT WHITE (-7420 4310);
FORCEPROP 1 LAST PACK_TYPE SM
J 0
(-7420 4200);
DISPLAY 0.617021 (-7420 4200);
PAINT SKYBLUE (-7420 4200);
FORCEPROP 2 LAST CDS_LIB mstr_discrete
J 0
(-7500 4300);
PAINT MONO (-7500 4300);
DISPLAY INVISIBLE (-7500 4300);
FORCEPROP 0 LAST TOLERANCE 1%
J 0
(-7575 4450);
PAINT SKYBLUE (-7575 4450);
DISPLAY INVISIBLE (-7575 4450);
FORCEPROP 2 LAST SEC_TYPE SM
J 0
(-7575 4525);
DISPLAY 1.659574 (-7575 4525);
PAINT ORANGE (-7575 4525);
DISPLAY INVISIBLE (-7575 4525);
FORCEPROP 2 LAST SEC 1
J 0
(-7575 4525);
DISPLAY 1.106383 (-7575 4525);
PAINT MONO (-7575 4525);
DISPLAY INVISIBLE (-7575 4525);
FORCEPROP 2 LAST CDS_LOCATION FB4A1
J 0
(-7595 4355);
DISPLAY 0.617021 (-7595 4355);
PAINT AQUA (-7595 4355);
DISPLAY INVISIBLE (-7595 4355);
FORCEPROP 1 LAST PATH I154
J 0
(-7595 4465);
DISPLAY 0.872340 (-7595 4465);
PAINT PURPLE (-7595 4465);
DISPLAY INVISIBLE (-7595 4465);
FORCEPROP 2 LAST ROOM PVPP_KLM_VR
J 0
(-7575 4450);
DISPLAY 1.659574 (-7575 4450);
PAINT GREEN (-7575 4450);
DISPLAY INVISIBLE (-7575 4450);
FORCEADD RES..1
(-4075 4200);
FORCEPROP 1 LAST WATTAGE 1/16W
J 2
(-4100 4025);
DISPLAY 0.617021 (-4100 4025);
PAINT SKYBLUE (-4100 4025);
FORCEPROP 1 LAST VALUE 0.0
J 2
(-4175 4075);
DISPLAY 0.617021 (-4175 4075);
PAINT SKYBLUE (-4175 4075);
FORCEPROP 1 LASTPIN (-4175 4200) $PN 1
J 0
(-4163 4212);
DISPLAY 0.617021 (-4163 4212);
PAINT WHITE (-4163 4212);
FORCEPROP 1 LAST TOLERANCE 5%
J 0
(-4125 4075);
DISPLAY 0.617021 (-4125 4075);
PAINT SKYBLUE (-4125 4075);
FORCEPROP 1 LAST PART_NUMBER G21497-005
J 0
(-4225 4125);
DISPLAY 0.617021 (-4225 4125);
PAINT BLUE (-4225 4125);
FORCEPROP 1 LAST LOCATION R4B13
J 0
(-4125 4250);
DISPLAY 0.617021 (-4125 4250);
PAINT AQUA (-4125 4250);
FORCEPROP 1 LAST MATERIAL CHIP
J 0
(-4075 4025);
DISPLAY 0.617021 (-4075 4025);
PAINT SKYBLUE (-4075 4025);
FORCEPROP 1 LAST PACK_TYPE 0402
J 0
(-4025 4075);
DISPLAY 0.617021 (-4025 4075);
PAINT SKYBLUE (-4025 4075);
FORCEPROP 1 LASTPIN (-3975 4200) $PN 2
J 0
(-4013 4212);
DISPLAY 0.617021 (-4013 4212);
PAINT WHITE (-4013 4212);
FORCEPROP 2 LAST REUSE_ID 13
J 0
(-4125 4400);
DISPLAY 1.042553 (-4125 4400);
PAINT ORANGE (-4125 4400);
DISPLAY INVISIBLE (-4125 4400);
FORCEPROP 2 LAST CDS_SEC 1
J 0
(-4125 4400);
DISPLAY 1.042553 (-4125 4400);
PAINT ORANGE (-4125 4400);
DISPLAY INVISIBLE (-4125 4400);
FORCEPROP 2 LAST $SEC 1
J 0
(-4125 4400);
DISPLAY 0.680851 (-4125 4400);
PAINT MONO (-4125 4400);
DISPLAY INVISIBLE (-4125 4400);
FORCEPROP 1 LAST PATH I155
J 0
(-4125 4350);
DISPLAY 0.978723 (-4125 4350);
PAINT WHITE (-4125 4350);
DISPLAY INVISIBLE (-4125 4350);
FORCEPROP 2 LAST ROOM PVPP_KLM_VR
J 0
(-4075 4200);
PAINT GREEN (-4075 4200);
DISPLAY INVISIBLE (-4075 4200);
FORCEPROP 2 LAST CDS_LIB mstr_discrete
J 0
(-4075 4200);
PAINT MONO (-4075 4200);
DISPLAY INVISIBLE (-4075 4200);
FORCEPROP 2 LAST BOM_COST PVPP_KLM_VR
J 0
(-4075 4200);
PAINT WHITE (-4075 4200);
DISPLAY INVISIBLE (-4075 4200);
FORCEADD OFFPAGE..2
(-2475 975);
FORCEPROP 2 LAST $XR0 190 
J 0
(-2286 975);
DISPLAY 0.638298 (-2286 975);
PAINT MONO (-2286 975);
FORCEPROP 2 LAST BOM_COST PVPP_KLM_VR
J 0
(-3175 1050);
DISPLAY 1.042553 (-3175 1050);
PAINT WHITE (-3175 1050);
DISPLAY INVISIBLE (-3175 1050);
FORCEPROP 1 LAST COMMENT_BODY TRUE
J 0
(-2520 880);
DISPLAY 0.872340 (-2520 880);
PAINT PEACH (-2520 880);
DISPLAY INVISIBLE (-2520 880);
FORCEPROP 2 LAST CDS_LIB mstr_standard
J 2
(-2475 975);
PAINT MONO (-2475 975);
DISPLAY INVISIBLE (-2475 975);
FORCEPROP 1 LAST OFFPAGE TRUE
J 0
(-2150 850);
PAINT GREEN (-2150 850);
DISPLAY INVISIBLE (-2150 850);
FORCEPROP 0 LAST TOLERANCE 1%
J 0
(-2300 1050);
PAINT SKYBLUE (-2300 1050);
DISPLAY INVISIBLE (-2300 1050);
FORCEPROP 2 LAST PATH I156
J 0
(-2175 1025);
DISPLAY 1.021277 (-2175 1025);
PAINT ORANGE (-2175 1025);
DISPLAY INVISIBLE (-2175 1025);
FORCEPROP 2 LAST ROOM PVPP_KLM_VR
J 0
(-2900 1050);
DISPLAY 1.042553 (-2900 1050);
PAINT GREEN (-2900 1050);
DISPLAY INVISIBLE (-2900 1050);
FORCEADD GND..1
(-3075 1925);
FORCEPROP 3 LASTPIN (-3075 1975) SIG_NAME GND\g
J 0
(-3065 1985);
DISPLAY 0.659574 (-3065 1985);
PAINT MONO (-3065 1985);
DISPLAY INVISIBLE (-3065 1985);
FORCEPROP 1 LAST VOLTAGE 0
J 0
(-3075 2000);
PAINT SKYBLUE (-3075 2000);
DISPLAY INVISIBLE (-3075 2000);
FORCEPROP 2 LAST CDS_LIB mstr_symbols
J 0
(-3075 1925);
PAINT MONO (-3075 1925);
DISPLAY INVISIBLE (-3075 1925);
FORCEPROP 1 LAST BODY_TYPE PLUMBING
J 0
(-3120 1882);
DISPLAY 0.340426 (-3120 1882);
PAINT GREEN (-3120 1882);
DISPLAY INVISIBLE (-3120 1882);
FORCEPROP 1 LAST PATH I157
J 0
(-3000 1925);
DISPLAY 0.872340 (-3000 1925);
PAINT AQUA (-3000 1925);
DISPLAY INVISIBLE (-3000 1925);
FORCEPROP 1 LAST SIZE 1B
J 0
(-3000 1950);
DISPLAY 0.893617 (-3000 1950);
PAINT GREEN (-3000 1950);
DISPLAY INVISIBLE (-3000 1950);
FORCEPROP 2 LAST ROOM PVPP_KLM_VR
J 0
(-3725 2075);
PAINT GREEN (-3725 2075);
DISPLAY INVISIBLE (-3725 2075);
FORCEPROP 2 LAST BOM_COST PVPP_KLM_VR
J 0
(-3975 2075);
DISPLAY 1.042553 (-3975 2075);
PAINT WHITE (-3975 2075);
DISPLAY INVISIBLE (-3975 2075);
FORCEPROP 1 LAST HDL_POWER GND
J 0
(-3075 2150);
DISPLAY 0.893617 (-3075 2150);
PAINT GREEN (-3075 2150);
DISPLAY INVISIBLE (-3075 2150);
FORCEADD GND..1
(-2650 3150);
FORCEPROP 3 LASTPIN (-2650 3200) SIG_NAME GND\g
J 0
(-2640 3210);
DISPLAY 0.659574 (-2640 3210);
PAINT MONO (-2640 3210);
DISPLAY INVISIBLE (-2640 3210);
FORCEPROP 2 LAST BOM_COST PVPP_KLM_VR
J 0
(-3550 3300);
DISPLAY 1.042553 (-3550 3300);
PAINT WHITE (-3550 3300);
DISPLAY INVISIBLE (-3550 3300);
FORCEPROP 2 LAST ROOM PVPP_KLM_VR
J 0
(-3300 3300);
PAINT GREEN (-3300 3300);
DISPLAY INVISIBLE (-3300 3300);
FORCEPROP 1 LAST BODY_TYPE PLUMBING
J 0
(-2695 3107);
DISPLAY 0.340426 (-2695 3107);
PAINT GREEN (-2695 3107);
DISPLAY INVISIBLE (-2695 3107);
FORCEPROP 1 LAST PATH I161
J 0
(-2575 3150);
DISPLAY 0.872340 (-2575 3150);
PAINT AQUA (-2575 3150);
DISPLAY INVISIBLE (-2575 3150);
FORCEPROP 1 LAST SIZE 1B
J 0
(-2575 3175);
DISPLAY 0.893617 (-2575 3175);
PAINT GREEN (-2575 3175);
DISPLAY INVISIBLE (-2575 3175);
FORCEPROP 2 LAST CDS_LIB mstr_symbols
J 0
(-2650 3225);
PAINT MONO (-2650 3225);
DISPLAY INVISIBLE (-2650 3225);
FORCEPROP 1 LAST VOLTAGE 0
J 0
(-2650 3225);
PAINT SKYBLUE (-2650 3225);
DISPLAY INVISIBLE (-2650 3225);
FORCEPROP 1 LAST HDL_POWER GND
J 0
(-2650 3375);
DISPLAY 0.893617 (-2650 3375);
PAINT GREEN (-2650 3375);
DISPLAY INVISIBLE (-2650 3375);
FORCEADD RES..2
(-2650 3350);
FORCEPROP 1 LASTPIN (-2650 3250) $PN 2
J 0
(-2645 3260);
DISPLAY 0.617021 (-2645 3260);
PAINT WHITE (-2645 3260);
FORCEPROP 1 LASTPIN (-2650 3450) $PN 1
J 0
(-2645 3412);
DISPLAY 0.617021 (-2645 3412);
PAINT WHITE (-2645 3412);
FORCEPROP 1 LAST LOCATION R4A7
J 0
(-2605 3450);
DISPLAY 0.617021 (-2605 3450);
PAINT AQUA (-2605 3450);
FORCEPROP 1 LAST WATTAGE 1/16W
J 0
(-2535 3275);
DISPLAY 0.617021 (-2535 3275);
PAINT SKYBLUE (-2535 3275);
FORCEPROP 1 LAST PACK_TYPE 0402
J 0
(-2535 3225);
DISPLAY 0.617021 (-2535 3225);
PAINT SKYBLUE (-2535 3225);
FORCEPROP 1 LAST TOLERANCE 5%
J 0
(-2530 3375);
DISPLAY 0.617021 (-2530 3375);
PAINT SKYBLUE (-2530 3375);
FORCEPROP 1 LAST VALUE 2.2
J 0
(-2530 3425);
DISPLAY 0.617021 (-2530 3425);
PAINT SKYBLUE (-2530 3425);
FORCEPROP 1 LAST MATERIAL EMPTY
J 0
(-2535 3325);
DISPLAY 0.617021 (-2535 3325);
PAINT RED (-2535 3325);
FORCEPROP 1 LAST PART_NUMBER G21497-016
J 0
(-2535 3175);
DISPLAY 0.617021 (-2535 3175);
PAINT BLUE (-2535 3175);
FORCEPROP 2 LAST CDS_LIB mstr_discrete
J 0
(-2650 3350);
PAINT MONO (-2650 3350);
DISPLAY INVISIBLE (-2650 3350);
FORCEPROP 2 LAST CDS_LOCATION R4A7
J 0
(-2605 3450);
DISPLAY 0.617021 (-2605 3450);
PAINT AQUA (-2605 3450);
DISPLAY INVISIBLE (-2605 3450);
FORCEPROP 2 LAST ROOM PVPP_KLM_VR
J 0
(-2600 3500);
PAINT GREEN (-2600 3500);
DISPLAY INVISIBLE (-2600 3500);
FORCEPROP 1 LAST PATH I162
J 0
(-2600 3525);
DISPLAY 0.978723 (-2600 3525);
PAINT WHITE (-2600 3525);
DISPLAY INVISIBLE (-2600 3525);
FORCEPROP 2 LAST BOM_COST PVPP_KLM_VR
J 0
(-2600 3525);
DISPLAY 1.042553 (-2600 3525);
PAINT WHITE (-2600 3525);
DISPLAY INVISIBLE (-2600 3525);
FORCEPROP 2 LAST $SEC 1
J 0
(-2600 3575);
DISPLAY 0.680851 (-2600 3575);
PAINT MONO (-2600 3575);
DISPLAY INVISIBLE (-2600 3575);
FORCEPROP 2 LAST CDS_SEC 1
J 0
(-2600 3575);
DISPLAY 1.042553 (-2600 3575);
PAINT ORANGE (-2600 3575);
DISPLAY INVISIBLE (-2600 3575);
FORCEPROP 2 LAST REUSE_ID 29
J 0
(-2600 3575);
DISPLAY 1.042553 (-2600 3575);
PAINT ORANGE (-2600 3575);
DISPLAY INVISIBLE (-2600 3575);
FORCEADD CAP..1
(-2650 3700);
FORCEPROP 1 LASTPIN (-2650 3600) $PN 2
J 0
(-2640 3580);
DISPLAY 0.617021 (-2640 3580);
PAINT WHITE (-2640 3580);
FORCEPROP 1 LASTPIN (-2650 3800) $PN 1
J 0
(-2640 3780);
DISPLAY 0.617021 (-2640 3780);
PAINT WHITE (-2640 3780);
FORCEPROP 1 LAST PART_NUMBER A36096-091
J 0
(-2525 3550);
DISPLAY 0.617021 (-2525 3550);
PAINT BLUE (-2525 3550);
FORCEPROP 1 LAST VOLTAGE 50V
J 0
(-2525 3700);
DISPLAY 0.617021 (-2525 3700);
PAINT SKYBLUE (-2525 3700);
FORCEPROP 1 LAST PACK_TYPE 0402LF
J 0
(-2525 3600);
DISPLAY 0.617021 (-2525 3600);
PAINT SKYBLUE (-2525 3600);
FORCEPROP 1 LAST TOLERANCE 10%
J 0
(-2525 3650);
DISPLAY 0.617021 (-2525 3650);
PAINT SKYBLUE (-2525 3650);
FORCEPROP 1 LAST VALUE 3300PF
J 0
(-2525 3750);
DISPLAY 0.617021 (-2525 3750);
PAINT SKYBLUE (-2525 3750);
FORCEPROP 1 LAST LOCATION C4A16
J 0
(-2550 3800);
DISPLAY 0.617021 (-2550 3800);
PAINT AQUA (-2550 3800);
FORCEPROP 1 LAST MATERIAL EMPTY
J 0
(-2425 3675);
DISPLAY 0.617021 (-2425 3675);
PAINT RED (-2425 3675);
FORCEPROP 2 LAST CDS_LIB mstr_discrete
J 0
(-2650 3700);
PAINT MONO (-2650 3700);
DISPLAY INVISIBLE (-2650 3700);
FORCEPROP 2 LAST ROOM PVPP_KLM_VR
J 0
(-2600 3825);
PAINT GREEN (-2600 3825);
DISPLAY INVISIBLE (-2600 3825);
FORCEPROP 1 LAST PATH I163
J 0
(-2600 3850);
DISPLAY 0.978723 (-2600 3850);
PAINT WHITE (-2600 3850);
DISPLAY INVISIBLE (-2600 3850);
FORCEPROP 2 LAST $SEC 1
J 0
(-2600 3900);
DISPLAY 0.680851 (-2600 3900);
PAINT MONO (-2600 3900);
DISPLAY INVISIBLE (-2600 3900);
FORCEPROP 2 LAST CDS_SEC 1
J 0
(-2600 3900);
DISPLAY 1.042553 (-2600 3900);
PAINT ORANGE (-2600 3900);
DISPLAY INVISIBLE (-2600 3900);
FORCEPROP 2 LAST BOM_COST PVPP_KLM_VR
J 0
(-2600 3850);
DISPLAY 1.042553 (-2600 3850);
PAINT WHITE (-2600 3850);
DISPLAY INVISIBLE (-2600 3850);
FORCEPROP 2 LAST REUSE_ID 26
J 0
(-2600 3900);
DISPLAY 1.042553 (-2600 3900);
PAINT ORANGE (-2600 3900);
DISPLAY INVISIBLE (-2600 3900);
FORCEPROP 2 LAST CDS_LOCATION C4A16
J 0
(-2550 3800);
DISPLAY 0.617021 (-2550 3800);
PAINT AQUA (-2550 3800);
DISPLAY INVISIBLE (-2550 3800);
FORCEADD INDUCTOR..1
(-2300 3850);
FORCEPROP 1 LAST VALUE 0.47UH
J 2
(-2430 3865);
DISPLAY 0.617021 (-2430 3865);
PAINT SKYBLUE (-2430 3865);
FORCEPROP 1 LASTPIN (-2400 3850) $PN 1
J 0
(-2400 3860);
DISPLAY 0.617021 (-2400 3860);
PAINT WHITE (-2400 3860);
FORCEPROP 1 LAST MATERIAL IND
J 0
(-2335 3790);
DISPLAY 0.617021 (-2335 3790);
PAINT SKYBLUE (-2335 3790);
FORCEPROP 1 LAST PART_NUMBER E13358-018
J 0
(-2400 3950);
DISPLAY 0.617021 (-2400 3950);
PAINT BLUE (-2400 3950);
FORCEPROP 1 LAST LOCATION L4A1
J 0
(-2350 3900);
DISPLAY 0.617021 (-2350 3900);
PAINT AQUA (-2350 3900);
FORCEPROP 1 LASTPIN (-2200 3850) $PN 2
J 2
(-2190 3860);
DISPLAY 0.617021 (-2190 3860);
PAINT WHITE (-2190 3860);
FORCEPROP 1 LAST PACK_TYPE SM
J 0
(-2160 3865);
DISPLAY 0.617021 (-2160 3865);
PAINT SKYBLUE (-2160 3865);
FORCEPROP 1 LAST PATH I164
J 0
(-2400 4000);
DISPLAY 0.978723 (-2400 4000);
PAINT ORANGE (-2400 4000);
DISPLAY INVISIBLE (-2400 4000);
FORCEPROP 2 LAST CDS_LOCATION L4A1
J 0
(-2350 3900);
DISPLAY 0.617021 (-2350 3900);
PAINT AQUA (-2350 3900);
DISPLAY INVISIBLE (-2350 3900);
FORCEPROP 2 LAST $SEC 1
J 0
(-2400 4050);
DISPLAY 0.680851 (-2400 4050);
PAINT MONO (-2400 4050);
DISPLAY INVISIBLE (-2400 4050);
FORCEPROP 2 LAST CDS_SEC 1
J 0
(-2400 4050);
DISPLAY 1.042553 (-2400 4050);
PAINT ORANGE (-2400 4050);
DISPLAY INVISIBLE (-2400 4050);
FORCEPROP 0 LAST TOLERANCE 1%
J 0
(-2400 4000);
PAINT SKYBLUE (-2400 4000);
DISPLAY INVISIBLE (-2400 4000);
FORCEPROP 2 LAST REUSE_ID 30
J 0
(-2400 4050);
DISPLAY 1.042553 (-2400 4050);
PAINT ORANGE (-2400 4050);
DISPLAY INVISIBLE (-2400 4050);
FORCEPROP 2 LAST BOM_COST PVPP_KLM_VR
J 0
(-2300 3850);
PAINT WHITE (-2300 3850);
DISPLAY INVISIBLE (-2300 3850);
FORCEPROP 2 LAST CDS_LIB mstr_discrete
J 0
(-2300 3850);
PAINT MONO (-2300 3850);
DISPLAY INVISIBLE (-2300 3850);
FORCEPROP 2 LAST ROOM PVPP_KLM_VR
J 2
(-2300 3850);
PAINT GREEN (-2300 3850);
DISPLAY INVISIBLE (-2300 3850);
FORCEADD GND..1
(-2075 3425);
FORCEPROP 3 LASTPIN (-2075 3475) SIG_NAME GND\g
J 0
(-2065 3485);
DISPLAY 0.659574 (-2065 3485);
PAINT MONO (-2065 3485);
DISPLAY INVISIBLE (-2065 3485);
FORCEPROP 2 LAST BOM_COST PVPP_KLM_VR
J 0
(-2925 3500);
DISPLAY 1.042553 (-2925 3500);
PAINT WHITE (-2925 3500);
DISPLAY INVISIBLE (-2925 3500);
FORCEPROP 2 LAST ROOM PVPP_KLM_VR
J 0
(-2650 3500);
DISPLAY 1.042553 (-2650 3500);
PAINT GREEN (-2650 3500);
DISPLAY INVISIBLE (-2650 3500);
FORCEPROP 1 LAST BODY_TYPE PLUMBING
J 0
(-2120 3382);
DISPLAY 0.340426 (-2120 3382);
PAINT GREEN (-2120 3382);
DISPLAY INVISIBLE (-2120 3382);
FORCEPROP 2 LAST CDS_LIB mstr_symbols
J 0
(-2075 3425);
PAINT MONO (-2075 3425);
DISPLAY INVISIBLE (-2075 3425);
FORCEPROP 1 LAST VOLTAGE 0
J 0
(-2075 3425);
PAINT SKYBLUE (-2075 3425);
DISPLAY INVISIBLE (-2075 3425);
FORCEPROP 1 LAST HDL_POWER GND
J 0
(-2075 3575);
DISPLAY 0.872340 (-2075 3575);
PAINT GREEN (-2075 3575);
DISPLAY INVISIBLE (-2075 3575);
FORCEPROP 1 LAST PATH I165
J 0
(-2000 3425);
DISPLAY 0.872340 (-2000 3425);
PAINT AQUA (-2000 3425);
DISPLAY INVISIBLE (-2000 3425);
FORCEPROP 1 LAST SIZE 1B
J 0
(-2000 3375);
DISPLAY 0.872340 (-2000 3375);
PAINT GREEN (-2000 3375);
DISPLAY INVISIBLE (-2000 3375);
FORCEADD GND..1
(-1750 3450);
FORCEPROP 3 LASTPIN (-1750 3500) SIG_NAME GND\g
J 0
(-1740 3510);
DISPLAY 0.659574 (-1740 3510);
PAINT MONO (-1740 3510);
DISPLAY INVISIBLE (-1740 3510);
FORCEPROP 2 LAST BOM_COST PVPP_KLM_VR
J 0
(-2600 3525);
DISPLAY 1.042553 (-2600 3525);
PAINT WHITE (-2600 3525);
DISPLAY INVISIBLE (-2600 3525);
FORCEPROP 2 LAST ROOM PVPP_KLM_VR
J 0
(-2325 3525);
DISPLAY 1.042553 (-2325 3525);
PAINT GREEN (-2325 3525);
DISPLAY INVISIBLE (-2325 3525);
FORCEPROP 1 LAST BODY_TYPE PLUMBING
J 0
(-1795 3407);
DISPLAY 0.340426 (-1795 3407);
PAINT GREEN (-1795 3407);
DISPLAY INVISIBLE (-1795 3407);
FORCEPROP 1 LAST VOLTAGE 0
J 0
(-1750 3450);
PAINT SKYBLUE (-1750 3450);
DISPLAY INVISIBLE (-1750 3450);
FORCEPROP 2 LAST CDS_LIB mstr_symbols
J 0
(-1750 3450);
PAINT MONO (-1750 3450);
DISPLAY INVISIBLE (-1750 3450);
FORCEPROP 1 LAST SIZE 1B
J 0
(-1675 3400);
DISPLAY 0.872340 (-1675 3400);
PAINT GREEN (-1675 3400);
DISPLAY INVISIBLE (-1675 3400);
FORCEPROP 1 LAST PATH I166
J 0
(-1675 3450);
DISPLAY 0.872340 (-1675 3450);
PAINT AQUA (-1675 3450);
DISPLAY INVISIBLE (-1675 3450);
FORCEPROP 1 LAST HDL_POWER GND
J 0
(-1750 3600);
DISPLAY 0.872340 (-1750 3600);
PAINT GREEN (-1750 3600);
DISPLAY INVISIBLE (-1750 3600);
FORCEADD CAPP..1
(-1750 3675);
FORCEPROP 1 LASTPIN (-1750 3575) $PN 2
J 0
(-1740 3560);
DISPLAY 0.617021 (-1740 3560);
PAINT WHITE (-1740 3560);
FORCEPROP 1 LASTPIN (-1750 3775) $PN 1
J 0
(-1740 3760);
DISPLAY 0.617021 (-1740 3760);
PAINT WHITE (-1740 3760);
FORCEPROP 1 LAST VOLTAGE 6.3V
J 0
(-1700 3625);
DISPLAY 0.617021 (-1700 3625);
PAINT SKYBLUE (-1700 3625);
FORCEPROP 1 LAST TOLERANCE 20%
J 0
(-1700 3675);
DISPLAY 0.617021 (-1700 3675);
PAINT SKYBLUE (-1700 3675);
FORCEPROP 1 LAST VALUE 330UF
J 0
(-1700 3725);
DISPLAY 0.617021 (-1700 3725);
PAINT SKYBLUE (-1700 3725);
FORCEPROP 1 LAST LOCATION C3B3
J 0
(-1700 3775);
DISPLAY 0.617021 (-1700 3775);
PAINT AQUA (-1700 3775);
FORCEPROP 1 LAST MATERIAL POSCAP
J 0
(-1700 3575);
DISPLAY 0.617021 (-1700 3575);
PAINT SKYBLUE (-1700 3575);
FORCEPROP 1 LAST PACK_TYPE 7343LF
J 0
(-1700 3525);
DISPLAY 0.617021 (-1700 3525);
PAINT SKYBLUE (-1700 3525);
FORCEPROP 1 LAST PART_NUMBER 724613-042
J 0
(-1700 3475);
DISPLAY 0.617021 (-1700 3475);
PAINT BLUE (-1700 3475);
FORCEPROP 2 LAST BOM_COST PVPP_KLM_VR
J 0
(-1750 3675);
DISPLAY 0.659574 (-1750 3675);
PAINT WHITE (-1750 3675);
DISPLAY INVISIBLE (-1750 3675);
FORCEPROP 2 LAST ROOM PVPP_KLM_VR
J 0
(-1750 3675);
PAINT GREEN (-1750 3675);
DISPLAY INVISIBLE (-1750 3675);
FORCEPROP 2 LAST CDS_LIB mstr_discrete
J 0
(-1750 3675);
PAINT MONO (-1750 3675);
DISPLAY INVISIBLE (-1750 3675);
FORCEPROP 2 LAST CDS_LOCATION C3B3
J 0
(-1700 3775);
DISPLAY 0.617021 (-1700 3775);
PAINT AQUA (-1700 3775);
DISPLAY INVISIBLE (-1700 3775);
FORCEPROP 1 LAST PATH I167
J 0
(-1700 3825);
DISPLAY 0.978723 (-1700 3825);
PAINT ORANGE (-1700 3825);
DISPLAY INVISIBLE (-1700 3825);
FORCEPROP 2 LAST $SEC 1
J 0
(-1700 3875);
DISPLAY 0.680851 (-1700 3875);
PAINT MONO (-1700 3875);
DISPLAY INVISIBLE (-1700 3875);
FORCEPROP 2 LAST CDS_SEC 1
J 0
(-1700 3875);
DISPLAY 1.042553 (-1700 3875);
PAINT ORANGE (-1700 3875);
DISPLAY INVISIBLE (-1700 3875);
FORCEPROP 2 LAST REUSE_ID 28
J 0
(-1700 3875);
DISPLAY 1.042553 (-1700 3875);
PAINT ORANGE (-1700 3875);
DISPLAY INVISIBLE (-1700 3875);
FORCEADD GND..1
(-1425 3450);
FORCEPROP 3 LASTPIN (-1425 3500) SIG_NAME GND\g
J 0
(-1415 3510);
DISPLAY 0.659574 (-1415 3510);
PAINT MONO (-1415 3510);
DISPLAY INVISIBLE (-1415 3510);
FORCEPROP 2 LAST BOM_COST PVPP_KLM_VR
J 0
(-2275 3525);
DISPLAY 1.042553 (-2275 3525);
PAINT WHITE (-2275 3525);
DISPLAY INVISIBLE (-2275 3525);
FORCEPROP 2 LAST ROOM PVPP_KLM_VR
J 0
(-2000 3525);
DISPLAY 1.042553 (-2000 3525);
PAINT GREEN (-2000 3525);
DISPLAY INVISIBLE (-2000 3525);
FORCEPROP 1 LAST BODY_TYPE PLUMBING
J 0
(-1470 3407);
DISPLAY 0.340426 (-1470 3407);
PAINT GREEN (-1470 3407);
DISPLAY INVISIBLE (-1470 3407);
FORCEPROP 2 LAST CDS_LIB mstr_symbols
J 0
(-1425 3450);
PAINT MONO (-1425 3450);
DISPLAY INVISIBLE (-1425 3450);
FORCEPROP 1 LAST VOLTAGE 0
J 0
(-1425 3450);
PAINT SKYBLUE (-1425 3450);
DISPLAY INVISIBLE (-1425 3450);
FORCEPROP 1 LAST PATH I175
J 0
(-1350 3450);
DISPLAY 0.872340 (-1350 3450);
PAINT AQUA (-1350 3450);
DISPLAY INVISIBLE (-1350 3450);
FORCEPROP 1 LAST SIZE 1B
J 0
(-1350 3400);
DISPLAY 0.872340 (-1350 3400);
PAINT GREEN (-1350 3400);
DISPLAY INVISIBLE (-1350 3400);
FORCEPROP 1 LAST HDL_POWER GND
J 0
(-1425 3600);
DISPLAY 0.872340 (-1425 3600);
PAINT GREEN (-1425 3600);
DISPLAY INVISIBLE (-1425 3600);
FORCEADD CAP..1
(-1150 3675);
FORCEPROP 1 LASTPIN (-1150 3575) $PN 2
J 0
(-1140 3555);
DISPLAY 0.617021 (-1140 3555);
PAINT WHITE (-1140 3555);
FORCEPROP 1 LAST VOLTAGE 4V
J 0
(-1100 3675);
DISPLAY 0.617021 (-1100 3675);
PAINT SKYBLUE (-1100 3675);
FORCEPROP 1 LASTPIN (-1150 3775) $PN 1
J 0
(-1140 3755);
DISPLAY 0.617021 (-1140 3755);
PAINT WHITE (-1140 3755);
FORCEPROP 1 LAST MATERIAL X6S
J 0
(-1100 3575);
DISPLAY 0.617021 (-1100 3575);
PAINT SKYBLUE (-1100 3575);
FORCEPROP 1 LAST PACK_TYPE 0805
J 0
(-1100 3475);
DISPLAY 0.617021 (-1100 3475);
PAINT SKYBLUE (-1100 3475);
FORCEPROP 1 LAST TOLERANCE 20%
J 0
(-1100 3625);
DISPLAY 0.617021 (-1100 3625);
PAINT SKYBLUE (-1100 3625);
FORCEPROP 1 LAST VALUE 47UF
J 0
(-1100 3725);
DISPLAY 0.617021 (-1100 3725);
PAINT SKYBLUE (-1100 3725);
FORCEPROP 1 LAST PART_NUMBER C95333-006
J 0
(-1100 3525);
DISPLAY 0.617021 (-1100 3525);
PAINT BLUE (-1100 3525);
FORCEPROP 1 LAST LOCATION C4B3
J 0
(-1100 3775);
DISPLAY 0.617021 (-1100 3775);
PAINT AQUA (-1100 3775);
FORCEPROP 2 LAST CDS_LIB mstr_discrete
J 0
(-1150 3675);
PAINT MONO (-1150 3675);
DISPLAY INVISIBLE (-1150 3675);
FORCEPROP 2 LAST BOM_COST PVPP_KLM_VR
J 0
(-1150 3675);
PAINT WHITE (-1150 3675);
DISPLAY INVISIBLE (-1150 3675);
FORCEPROP 2 LAST CDS_LOCATION C4B3
J 0
(-1100 3775);
DISPLAY 0.617021 (-1100 3775);
PAINT AQUA (-1100 3775);
DISPLAY INVISIBLE (-1100 3775);
FORCEPROP 2 LAST ROOM PVPP_KLM_VR
J 0
(-1150 3675);
PAINT GREEN (-1150 3675);
DISPLAY INVISIBLE (-1150 3675);
FORCEPROP 1 LAST PATH I177
J 0
(-1100 3825);
DISPLAY 0.978723 (-1100 3825);
PAINT WHITE (-1100 3825);
DISPLAY INVISIBLE (-1100 3825);
FORCEPROP 2 LAST REUSE_ID 33
J 0
(-1100 3875);
DISPLAY 1.042553 (-1100 3875);
PAINT ORANGE (-1100 3875);
DISPLAY INVISIBLE (-1100 3875);
FORCEPROP 2 LAST CDS_SEC 1
J 0
(-1100 3875);
DISPLAY 1.042553 (-1100 3875);
PAINT ORANGE (-1100 3875);
DISPLAY INVISIBLE (-1100 3875);
FORCEPROP 2 LAST $SEC 1
J 0
(-1100 3875);
DISPLAY 0.680851 (-1100 3875);
PAINT MONO (-1100 3875);
DISPLAY INVISIBLE (-1100 3875);
FORCEADD GND..1
(-1150 3475);
FORCEPROP 3 LASTPIN (-1150 3525) SIG_NAME GND\g
J 0
(-1140 3535);
DISPLAY 0.659574 (-1140 3535);
PAINT MONO (-1140 3535);
DISPLAY INVISIBLE (-1140 3535);
FORCEPROP 2 LAST ROOM PVPP_KLM_VR
J 0
(-1725 3550);
DISPLAY 1.042553 (-1725 3550);
PAINT GREEN (-1725 3550);
DISPLAY INVISIBLE (-1725 3550);
FORCEPROP 2 LAST BOM_COST PVPP_KLM_VR
J 0
(-2000 3550);
DISPLAY 1.042553 (-2000 3550);
PAINT WHITE (-2000 3550);
DISPLAY INVISIBLE (-2000 3550);
FORCEPROP 1 LAST BODY_TYPE PLUMBING
J 0
(-1195 3432);
DISPLAY 0.340426 (-1195 3432);
PAINT GREEN (-1195 3432);
DISPLAY INVISIBLE (-1195 3432);
FORCEPROP 1 LAST PATH I178
J 0
(-1075 3475);
DISPLAY 0.872340 (-1075 3475);
PAINT AQUA (-1075 3475);
DISPLAY INVISIBLE (-1075 3475);
FORCEPROP 1 LAST SIZE 1B
J 0
(-1075 3425);
DISPLAY 0.872340 (-1075 3425);
PAINT GREEN (-1075 3425);
DISPLAY INVISIBLE (-1075 3425);
FORCEPROP 2 LAST CDS_LIB mstr_symbols
J 0
(-1150 3475);
PAINT MONO (-1150 3475);
DISPLAY INVISIBLE (-1150 3475);
FORCEPROP 1 LAST VOLTAGE 0
J 0
(-1150 3475);
PAINT SKYBLUE (-1150 3475);
DISPLAY INVISIBLE (-1150 3475);
FORCEPROP 1 LAST HDL_POWER GND
J 0
(-1150 3625);
DISPLAY 0.872340 (-1150 3625);
PAINT GREEN (-1150 3625);
DISPLAY INVISIBLE (-1150 3625);
FORCEADD GND..1
(-850 3500);
FORCEPROP 3 LASTPIN (-850 3550) SIG_NAME GND\g
J 0
(-840 3560);
DISPLAY 0.659574 (-840 3560);
PAINT MONO (-840 3560);
DISPLAY INVISIBLE (-840 3560);
FORCEPROP 2 LAST BOM_COST PVPP_KLM_VR
J 0
(-1700 3575);
DISPLAY 1.042553 (-1700 3575);
PAINT WHITE (-1700 3575);
DISPLAY INVISIBLE (-1700 3575);
FORCEPROP 2 LAST ROOM PVPP_KLM_VR
J 0
(-1425 3575);
DISPLAY 1.042553 (-1425 3575);
PAINT GREEN (-1425 3575);
DISPLAY INVISIBLE (-1425 3575);
FORCEPROP 1 LAST SIZE 1B
J 0
(-775 3450);
DISPLAY 0.872340 (-775 3450);
PAINT GREEN (-775 3450);
DISPLAY INVISIBLE (-775 3450);
FORCEPROP 1 LAST BODY_TYPE PLUMBING
J 0
(-895 3457);
DISPLAY 0.340426 (-895 3457);
PAINT GREEN (-895 3457);
DISPLAY INVISIBLE (-895 3457);
FORCEPROP 2 LAST CDS_LIB mstr_symbols
J 0
(-850 3500);
PAINT MONO (-850 3500);
DISPLAY INVISIBLE (-850 3500);
FORCEPROP 1 LAST VOLTAGE 0
J 0
(-850 3500);
PAINT SKYBLUE (-850 3500);
DISPLAY INVISIBLE (-850 3500);
FORCEPROP 1 LAST PATH I179
J 0
(-775 3500);
DISPLAY 0.872340 (-775 3500);
PAINT AQUA (-775 3500);
DISPLAY INVISIBLE (-775 3500);
FORCEPROP 1 LAST HDL_POWER GND
J 0
(-850 3650);
DISPLAY 0.872340 (-850 3650);
PAINT GREEN (-850 3650);
DISPLAY INVISIBLE (-850 3650);
FORCEADD CAP..1
(-850 3650);
FORCEPROP 1 LASTPIN (-850 3550) $PN 2
J 0
(-840 3530);
DISPLAY 0.617021 (-840 3530);
PAINT WHITE (-840 3530);
FORCEPROP 1 LAST MATERIAL X6S
J 0
(-800 3550);
DISPLAY 0.617021 (-800 3550);
PAINT SKYBLUE (-800 3550);
FORCEPROP 1 LAST PACK_TYPE 0805
J 0
(-800 3450);
DISPLAY 0.617021 (-800 3450);
PAINT SKYBLUE (-800 3450);
FORCEPROP 1 LASTPIN (-850 3750) $PN 1
J 0
(-840 3730);
DISPLAY 0.617021 (-840 3730);
PAINT WHITE (-840 3730);
FORCEPROP 1 LAST VOLTAGE 4V
J 0
(-800 3650);
DISPLAY 0.617021 (-800 3650);
PAINT SKYBLUE (-800 3650);
FORCEPROP 1 LAST TOLERANCE 20%
J 0
(-800 3600);
DISPLAY 0.617021 (-800 3600);
PAINT SKYBLUE (-800 3600);
FORCEPROP 1 LAST VALUE 47UF
J 0
(-800 3700);
DISPLAY 0.617021 (-800 3700);
PAINT SKYBLUE (-800 3700);
FORCEPROP 1 LAST LOCATION C4B2
J 0
(-800 3750);
DISPLAY 0.617021 (-800 3750);
PAINT AQUA (-800 3750);
FORCEPROP 1 LAST PART_NUMBER C95333-006
J 0
(-800 3500);
DISPLAY 0.617021 (-800 3500);
PAINT BLUE (-800 3500);
FORCEPROP 2 LAST ROOM PVPP_KLM_VR
J 0
(-850 3650);
PAINT GREEN (-850 3650);
DISPLAY INVISIBLE (-850 3650);
FORCEPROP 2 LAST CDS_LOCATION C4B2
J 0
(-800 3750);
DISPLAY 0.617021 (-800 3750);
PAINT AQUA (-800 3750);
DISPLAY INVISIBLE (-800 3750);
FORCEPROP 2 LAST BOM_COST PVPP_KLM_VR
J 0
(-850 3650);
PAINT WHITE (-850 3650);
DISPLAY INVISIBLE (-850 3650);
FORCEPROP 2 LAST CDS_LIB mstr_discrete
J 0
(-850 3650);
PAINT MONO (-850 3650);
DISPLAY INVISIBLE (-850 3650);
FORCEPROP 1 LAST PATH I180
J 0
(-800 3800);
DISPLAY 0.978723 (-800 3800);
PAINT WHITE (-800 3800);
DISPLAY INVISIBLE (-800 3800);
FORCEPROP 2 LAST REUSE_ID 33
J 0
(-800 3850);
DISPLAY 1.042553 (-800 3850);
PAINT ORANGE (-800 3850);
DISPLAY INVISIBLE (-800 3850);
FORCEPROP 2 LAST CDS_SEC 1
J 0
(-800 3850);
DISPLAY 1.042553 (-800 3850);
PAINT ORANGE (-800 3850);
DISPLAY INVISIBLE (-800 3850);
FORCEPROP 2 LAST $SEC 1
J 0
(-800 3850);
DISPLAY 0.680851 (-800 3850);
PAINT MONO (-800 3850);
DISPLAY INVISIBLE (-800 3850);
FORCEADD CAP..2
R 2
(-3375 4200);
FORCEPROP 1 LAST MATERIAL X7R
J 2
(-3375 4050);
DISPLAY 0.617021 (-3375 4050);
PAINT SKYBLUE (-3375 4050);
FORCEPROP 1 LAST PACK_TYPE 0603LF
J 1
(-3375 4000);
DISPLAY 0.617021 (-3375 4000);
PAINT SKYBLUE (-3375 4000);
FORCEPROP 1 LAST TOLERANCE 10%
J 0
(-3375 4050);
DISPLAY 0.617021 (-3375 4050);
PAINT SKYBLUE (-3375 4050);
FORCEPROP 1 LASTPIN (-3475 4200) $PN 2
J 2
(-3460 4215);
DISPLAY 0.617021 (-3460 4215);
PAINT WHITE (-3460 4215);
FORCEPROP 1 LAST VOLTAGE 25V
J 2
(-3375 4100);
DISPLAY 0.617021 (-3375 4100);
PAINT SKYBLUE (-3375 4100);
FORCEPROP 1 LAST LOCATION C4B15
J 1
(-3375 4300);
DISPLAY 0.617021 (-3375 4300);
PAINT AQUA (-3375 4300);
FORCEPROP 1 LAST PART_NUMBER 602433-020
J 1
(-3375 4250);
DISPLAY 0.617021 (-3375 4250);
PAINT BLUE (-3375 4250);
FORCEPROP 1 LAST VALUE 0.1UF
J 0
(-3375 4100);
DISPLAY 0.617021 (-3375 4100);
PAINT SKYBLUE (-3375 4100);
FORCEPROP 1 LASTPIN (-3275 4200) $PN 1
J 2
(-3265 4215);
DISPLAY 0.617021 (-3265 4215);
PAINT WHITE (-3265 4215);
FORCEPROP 2 LAST BOM_COST PVPP_KLM_VR
J 0
(-3420 4360);
DISPLAY 1.042553 (-3420 4360);
PAINT WHITE (-3420 4360);
DISPLAY INVISIBLE (-3420 4360);
FORCEPROP 2 LAST REUSE_ID 27
J 0
(-3375 4450);
DISPLAY 1.042553 (-3375 4450);
PAINT ORANGE (-3375 4450);
DISPLAY INVISIBLE (-3375 4450);
FORCEPROP 2 LAST ROOM PVPP_KLM_VR
J 2
(-3375 4325);
DISPLAY 0.765957 (-3375 4325);
PAINT GREEN (-3375 4325);
DISPLAY INVISIBLE (-3375 4325);
FORCEPROP 1 LAST PATH I182
J 2
(-3375 4400);
DISPLAY 0.978723 (-3375 4400);
PAINT WHITE (-3375 4400);
DISPLAY INVISIBLE (-3375 4400);
FORCEPROP 2 LAST CDS_LIB mstr_discrete
J 0
(-3375 4200);
PAINT MONO (-3375 4200);
DISPLAY INVISIBLE (-3375 4200);
FORCEPROP 2 LAST CDS_SEC 1
J 0
(-3420 4410);
DISPLAY 1.042553 (-3420 4410);
PAINT ORANGE (-3420 4410);
DISPLAY INVISIBLE (-3420 4410);
FORCEPROP 2 LAST $SEC 1
J 0
(-3375 4450);
DISPLAY 0.680851 (-3375 4450);
PAINT MONO (-3375 4450);
DISPLAY INVISIBLE (-3375 4450);
FORCEADD RES..2
(-2075 3675);
FORCEPROP 1 LASTPIN (-2075 3775) $PN 1
J 0
(-2070 3737);
DISPLAY 0.617021 (-2070 3737);
PAINT WHITE (-2070 3737);
FORCEPROP 1 LASTPIN (-2075 3575) $PN 2
J 0
(-2070 3585);
DISPLAY 0.617021 (-2070 3585);
PAINT WHITE (-2070 3585);
FORCEPROP 1 LAST PACK_TYPE 0603
J 0
(-2035 3500);
DISPLAY 0.617021 (-2035 3500);
PAINT SKYBLUE (-2035 3500);
FORCEPROP 1 LAST PART_NUMBER G22026-003
J 0
(-2035 3550);
DISPLAY 0.617021 (-2035 3550);
PAINT BLUE (-2035 3550);
FORCEPROP 1 LAST WATTAGE 1/10W
J 0
(-2035 3650);
DISPLAY 0.617021 (-2035 3650);
PAINT SKYBLUE (-2035 3650);
FORCEPROP 1 LAST MATERIAL CHIP
J 0
(-2035 3600);
DISPLAY 0.617021 (-2035 3600);
PAINT SKYBLUE (-2035 3600);
FORCEPROP 1 LAST TOLERANCE 1%
J 0
(-2030 3700);
DISPLAY 0.617021 (-2030 3700);
PAINT SKYBLUE (-2030 3700);
FORCEPROP 1 LAST VALUE 120.0
J 0
(-2030 3750);
DISPLAY 0.617021 (-2030 3750);
PAINT SKYBLUE (-2030 3750);
FORCEPROP 1 LAST LOCATION R4B2
J 0
(-2030 3800);
DISPLAY 0.617021 (-2030 3800);
PAINT AQUA (-2030 3800);
FORCEPROP 2 LAST CDS_LIB mstr_discrete
J 0
(-2075 3675);
PAINT MONO (-2075 3675);
DISPLAY INVISIBLE (-2075 3675);
FORCEPROP 2 LAST ROOM PVPP_KLM_VR
J 0
(-2030 3830);
PAINT GREEN (-2030 3830);
DISPLAY INVISIBLE (-2030 3830);
FORCEPROP 1 LAST PATH I183
J 0
(-2025 3850);
DISPLAY 0.978723 (-2025 3850);
PAINT WHITE (-2025 3850);
DISPLAY INVISIBLE (-2025 3850);
FORCEPROP 2 LAST CDS_LOCATION R4B2
J 0
(-2030 3800);
DISPLAY 0.617021 (-2030 3800);
PAINT AQUA (-2030 3800);
DISPLAY INVISIBLE (-2030 3800);
FORCEPROP 2 LAST $SEC 1
J 0
(-2025 3900);
DISPLAY 0.680851 (-2025 3900);
PAINT MONO (-2025 3900);
DISPLAY INVISIBLE (-2025 3900);
FORCEPROP 2 LAST CDS_SEC 1
J 0
(-2025 3900);
DISPLAY 1.042553 (-2025 3900);
PAINT ORANGE (-2025 3900);
DISPLAY INVISIBLE (-2025 3900);
FORCEPROP 2 LAST BOM_COST PVPP_KLM_VR
J 0
(-2030 3855);
DISPLAY 1.042553 (-2030 3855);
PAINT WHITE (-2030 3855);
DISPLAY INVISIBLE (-2030 3855);
FORCEPROP 2 LAST REUSE_ID 34
J 0
(-2025 3900);
DISPLAY 1.042553 (-2025 3900);
PAINT ORANGE (-2025 3900);
DISPLAY INVISIBLE (-2025 3900);
FORCEADD NCP3232L..1
(-3800 2875);
FORCEPROP 2 LASTPIN (-4300 2025) $PN 5
J 2
(-4310 2035);
DISPLAY 0.617021 (-4310 2035);
PAINT ORANGE (-4310 2035);
FORCEPROP 2 LASTPIN (-4300 2525) $PN 7
J 2
(-4310 2535);
DISPLAY 0.617021 (-4310 2535);
PAINT ORANGE (-4310 2535);
FORCEPROP 2 LASTPIN (-4300 2825) $PN 40
J 2
(-4310 2835);
DISPLAY 0.617021 (-4310 2835);
PAINT ORANGE (-4310 2835);
FORCEPROP 2 LASTPIN (-4300 3025) $PN 38
J 2
(-4310 3035);
DISPLAY 0.617021 (-4310 3035);
PAINT ORANGE (-4310 3035);
FORCEPROP 2 LASTPIN (-4300 2725) $PN 1
J 2
(-4310 2735);
DISPLAY 0.617021 (-4310 2735);
PAINT ORANGE (-4310 2735);
FORCEPROP 2 LASTPIN (-4300 2625) $PN 4
J 2
(-4310 2635);
DISPLAY 0.617021 (-4310 2635);
PAINT ORANGE (-4310 2635);
FORCEPROP 2 LASTPIN (-4300 2925) $PN 6
J 2
(-4310 2935);
DISPLAY 0.617021 (-4310 2935);
PAINT ORANGE (-4310 2935);
FORCEPROP 2 LASTPIN (-4300 3225) $PN 10
J 2
(-4310 3235);
DISPLAY 0.617021 (-4310 3235);
PAINT ORANGE (-4310 3235);
FORCEPROP 2 LASTPIN (-4300 3275) $PN 11
J 2
(-4310 3285);
DISPLAY 0.617021 (-4310 3285);
PAINT ORANGE (-4310 3285);
FORCEPROP 2 LASTPIN (-4300 3325) $PN 12
J 2
(-4310 3335);
DISPLAY 0.617021 (-4310 3335);
PAINT ORANGE (-4310 3335);
FORCEPROP 2 LASTPIN (-4300 3375) $PN 13
J 2
(-4310 3385);
DISPLAY 0.617021 (-4310 3385);
PAINT ORANGE (-4310 3385);
FORCEPROP 2 LASTPIN (-4300 3425) $PN 14
J 2
(-4310 3435);
DISPLAY 0.617021 (-4310 3435);
PAINT ORANGE (-4310 3435);
FORCEPROP 2 LASTPIN (-4300 3475) $PN 42
J 2
(-4310 3485);
DISPLAY 0.617021 (-4310 3485);
PAINT ORANGE (-4310 3485);
FORCEPROP 2 LASTPIN (-4300 3125) $PN 8
J 2
(-4310 3135);
DISPLAY 0.617021 (-4310 3135);
PAINT ORANGE (-4310 3135);
FORCEPROP 2 LASTPIN (-4300 3175) $PN 9
J 2
(-4310 3185);
DISPLAY 0.617021 (-4310 3185);
PAINT ORANGE (-4310 3185);
FORCEPROP 2 LASTPIN (-4300 3575) $PN 39
J 2
(-4310 3585);
DISPLAY 0.617021 (-4310 3585);
PAINT ORANGE (-4310 3585);
FORCEPROP 1 LAST MATERIAL IC
J 0
(-4250 3775);
DISPLAY 0.617021 (-4250 3775);
PAINT SKYBLUE (-4250 3775);
FORCEPROP 1 LAST LOCATION EU4A3
J 0
(-4250 3825);
DISPLAY 0.617021 (-4250 3825);
PAINT AQUA (-4250 3825);
FORCEPROP 1 LAST PART_NUMBER H86355-001
J 0
(-4250 1875);
DISPLAY 0.617021 (-4250 1875);
PAINT BLUE (-4250 1875);
FORCEPROP 2 LASTPIN (-3300 2025) $PN 41
J 0
(-3290 2035);
DISPLAY 0.617021 (-3290 2035);
PAINT ORANGE (-3290 2035);
FORCEPROP 2 LASTPIN (-3300 2075) $PN 16
J 0
(-3290 2085);
DISPLAY 0.617021 (-3290 2085);
PAINT ORANGE (-3290 2085);
FORCEPROP 2 LASTPIN (-3300 2225) $PN 19
J 0
(-3290 2235);
DISPLAY 0.617021 (-3290 2235);
PAINT ORANGE (-3290 2235);
FORCEPROP 2 LASTPIN (-3300 2175) $PN 18
J 0
(-3290 2185);
DISPLAY 0.617021 (-3290 2185);
PAINT ORANGE (-3290 2185);
FORCEPROP 2 LASTPIN (-3300 2125) $PN 17
J 0
(-3290 2135);
DISPLAY 0.617021 (-3290 2135);
PAINT ORANGE (-3290 2135);
FORCEPROP 2 LASTPIN (-3300 2275) $PN 20
J 0
(-3290 2285);
DISPLAY 0.617021 (-3290 2285);
PAINT ORANGE (-3290 2285);
FORCEPROP 2 LASTPIN (-3300 2325) $PN 21
J 0
(-3290 2335);
DISPLAY 0.617021 (-3290 2335);
PAINT ORANGE (-3290 2335);
FORCEPROP 2 LASTPIN (-3300 2475) $PN 24
J 0
(-3290 2485);
DISPLAY 0.617021 (-3290 2485);
PAINT ORANGE (-3290 2485);
FORCEPROP 2 LASTPIN (-3300 2425) $PN 23
J 0
(-3290 2435);
DISPLAY 0.617021 (-3290 2435);
PAINT ORANGE (-3290 2435);
FORCEPROP 2 LASTPIN (-3300 2375) $PN 22
J 0
(-3290 2385);
DISPLAY 0.617021 (-3290 2385);
PAINT ORANGE (-3290 2385);
FORCEPROP 2 LASTPIN (-3300 2525) $PN 25
J 0
(-3290 2535);
DISPLAY 0.617021 (-3290 2535);
PAINT ORANGE (-3290 2535);
FORCEPROP 2 LASTPIN (-3300 2675) $PN 28
J 0
(-3290 2685);
DISPLAY 0.617021 (-3290 2685);
PAINT ORANGE (-3290 2685);
FORCEPROP 2 LASTPIN (-3300 2725) $PN 37
J 0
(-3290 2735);
DISPLAY 0.617021 (-3290 2735);
PAINT ORANGE (-3290 2735);
FORCEPROP 2 LASTPIN (-3300 2625) $PN 27
J 0
(-3290 2635);
DISPLAY 0.617021 (-3290 2635);
PAINT ORANGE (-3290 2635);
FORCEPROP 2 LASTPIN (-3300 2575) $PN 26
J 0
(-3290 2585);
DISPLAY 0.617021 (-3290 2585);
PAINT ORANGE (-3290 2585);
FORCEPROP 2 LASTPIN (-3300 3025) $PN 35
J 0
(-3290 3035);
DISPLAY 0.617021 (-3290 3035);
PAINT ORANGE (-3290 3035);
FORCEPROP 2 LASTPIN (-3300 2925) $PN 2
J 0
(-3290 2935);
DISPLAY 0.617021 (-3290 2935);
PAINT ORANGE (-3290 2935);
FORCEPROP 2 LASTPIN (-3300 2825) $PN 3
J 0
(-3290 2835);
DISPLAY 0.617021 (-3290 2835);
PAINT ORANGE (-3290 2835);
FORCEPROP 2 LASTPIN (-3300 3175) $PN 29
J 0
(-3290 3185);
DISPLAY 0.617021 (-3290 3185);
PAINT ORANGE (-3290 3185);
FORCEPROP 2 LASTPIN (-3300 3125) $PN 15
J 0
(-3290 3135);
DISPLAY 0.617021 (-3290 3135);
PAINT ORANGE (-3290 3135);
FORCEPROP 2 LASTPIN (-3300 3275) $PN 31
J 0
(-3290 3285);
DISPLAY 0.617021 (-3290 3285);
PAINT ORANGE (-3290 3285);
FORCEPROP 2 LASTPIN (-3300 3225) $PN 30
J 0
(-3290 3235);
DISPLAY 0.617021 (-3290 3235);
PAINT ORANGE (-3290 3235);
FORCEPROP 2 LASTPIN (-3300 3425) $PN 34
J 0
(-3290 3435);
DISPLAY 0.617021 (-3290 3435);
PAINT ORANGE (-3290 3435);
FORCEPROP 2 LASTPIN (-3300 3375) $PN 33
J 0
(-3290 3385);
DISPLAY 0.617021 (-3290 3385);
PAINT ORANGE (-3290 3385);
FORCEPROP 2 LASTPIN (-3300 3325) $PN 32
J 0
(-3290 3335);
DISPLAY 0.617021 (-3290 3335);
PAINT ORANGE (-3290 3335);
FORCEPROP 2 LASTPIN (-3300 3475) $PN 43
J 0
(-3290 3485);
DISPLAY 0.617021 (-3290 3485);
PAINT ORANGE (-3290 3485);
FORCEPROP 2 LASTPIN (-3300 3575) $PN 36
J 0
(-3290 3585);
DISPLAY 0.617021 (-3290 3585);
PAINT ORANGE (-3290 3585);
FORCEPROP 2 LAST CDS_LOCATION EU4A3
J 0
(-4250 3825);
DISPLAY 0.617021 (-4250 3825);
PAINT AQUA (-4250 3825);
DISPLAY INVISIBLE (-4250 3825);
FORCEPROP 2 LAST SEC 1
J 0
(-4250 3875);
DISPLAY 0.680851 (-4250 3875);
PAINT MONO (-4250 3875);
DISPLAY INVISIBLE (-4250 3875);
FORCEPROP 2 LAST SEC_TYPE SM
J 0
(-4250 3875);
DISPLAY 1.021277 (-4250 3875);
PAINT ORANGE (-4250 3875);
DISPLAY INVISIBLE (-4250 3875);
FORCEPROP 1 LAST PACK_TYPE SM
J 0
(-4250 3875);
PAINT SKYBLUE (-4250 3875);
DISPLAY INVISIBLE (-4250 3875);
FORCEPROP 2 LAST CDS_LIB mstr_vreg
J 0
(-3800 2875);
PAINT ORANGE (-3800 2875);
DISPLAY INVISIBLE (-3800 2875);
FORCEPROP 1 LAST CDS_LMAN_SYM_OUTLINE -450,850,450,-900
J 0
(-3800 2875);
DISPLAY 0.468085 (-3800 2875);
PAINT GREEN (-3800 2875);
DISPLAY INVISIBLE (-3800 2875);
FORCEPROP 1 LAST PATH I184
J 0
(-3750 3775);
PAINT GREEN (-3750 3775);
DISPLAY INVISIBLE (-3750 3775);
FORCEADD PVPP_KLM..1
(-800 3975);
FORCEPROP 3 LASTPIN (-800 3925) SIG_NAME PVPP_KLM\g
J 0
(-790 3935);
DISPLAY 0.659574 (-790 3935);
PAINT MONO (-790 3935);
DISPLAY INVISIBLE (-790 3935);
FORCEPROP 1 LAST VOLTAGE 2.5V
J 0
(-845 3932);
DISPLAY 0.340426 (-845 3932);
PAINT SKYBLUE (-845 3932);
DISPLAY INVISIBLE (-845 3932);
FORCEPROP 1 LAST BODY_TYPE PLUMBING
J 0
(-845 3932);
DISPLAY 0.340426 (-845 3932);
PAINT GREEN (-845 3932);
DISPLAY INVISIBLE (-845 3932);
FORCEPROP 2 LAST CDS_LIB mstr_symbols
J 0
(-800 3975);
PAINT ORANGE (-800 3975);
DISPLAY INVISIBLE (-800 3975);
FORCEPROP 1 LAST HDL_POWER PVPP_KLM
J 1
(-800 4025);
DISPLAY 0.872340 (-800 4025);
PAINT GREEN (-800 4025);
DISPLAY INVISIBLE (-800 4025);
FORCEPROP 1 LAST PATH I185
J 0
(-750 4000);
DISPLAY 0.872340 (-750 4000);
PAINT AQUA (-750 4000);
DISPLAY INVISIBLE (-750 4000);
FORCEPROP 2 LAST ROOM PVPP_KLM_VR
J 0
(-550 4075);
PAINT ORANGE (-550 4075);
DISPLAY INVISIBLE (-550 4075);
FORCEPROP 2 LAST BOM_COST PVPP_KLM_VR
J 0
(-725 4075);
PAINT MONO (-725 4075);
DISPLAY INVISIBLE (-725 4075);
FORCEADD AGND_SCSI..1
(-6300 2075);
FORCEPROP 3 LASTPIN (-6300 2125) SIG_NAME AGND_PVPP_KLM\g
J 0
(-6290 2135);
DISPLAY 0.659574 (-6290 2135);
PAINT MONO (-6290 2135);
DISPLAY INVISIBLE (-6290 2135);
FORCEPROP 1 LAST HDL_POWER AGND_PVPP_KLM
J 1
(-6225 2000);
DISPLAY 0.617021 (-6225 2000);
PAINT GREEN (-6225 2000);
FORCEPROP 1 LAST BODY_TYPE PLUMBING
J 0
(-6345 2032);
DISPLAY 0.340426 (-6345 2032);
PAINT GREEN (-6345 2032);
DISPLAY INVISIBLE (-6345 2032);
FORCEPROP 1 LAST VOLTAGE 0.0V
J 0
(-6345 2032);
DISPLAY 0.340426 (-6345 2032);
PAINT SKYBLUE (-6345 2032);
DISPLAY INVISIBLE (-6345 2032);
FORCEPROP 2 LAST ROOM PVPP_KLM_VR
J 0
(-6450 2025);
DISPLAY 1.042553 (-6450 2025);
PAINT GREEN (-6450 2025);
DISPLAY INVISIBLE (-6450 2025);
FORCEPROP 2 LAST BOM_COST PVPP_KLM_VR
J 0
(-6450 2025);
DISPLAY 1.042553 (-6450 2025);
PAINT WHITE (-6450 2025);
DISPLAY INVISIBLE (-6450 2025);
FORCEPROP 2 LAST CDS_LIB mstr_symbols
J 0
(-6300 2075);
PAINT MONO (-6300 2075);
DISPLAY INVISIBLE (-6300 2075);
FORCEPROP 1 LAST PATH I187
J 0
(-6225 2075);
DISPLAY 0.872340 (-6225 2075);
PAINT AQUA (-6225 2075);
DISPLAY INVISIBLE (-6225 2075);
FORCEADD AGND_SCSI..1
(-5600 2100);
FORCEPROP 3 LASTPIN (-5600 2150) SIG_NAME AGND_PVPP_KLM\g
J 0
(-5590 2160);
DISPLAY 0.659574 (-5590 2160);
PAINT MONO (-5590 2160);
DISPLAY INVISIBLE (-5590 2160);
FORCEPROP 1 LAST HDL_POWER AGND_PVPP_KLM
J 1
(-5525 2025);
DISPLAY 0.617021 (-5525 2025);
PAINT GREEN (-5525 2025);
FORCEPROP 2 LAST ROOM PVPP_KLM_VR
J 0
(-5750 2050);
DISPLAY 1.042553 (-5750 2050);
PAINT GREEN (-5750 2050);
DISPLAY INVISIBLE (-5750 2050);
FORCEPROP 1 LAST BODY_TYPE PLUMBING
J 0
(-5645 2057);
DISPLAY 0.340426 (-5645 2057);
PAINT GREEN (-5645 2057);
DISPLAY INVISIBLE (-5645 2057);
FORCEPROP 2 LAST BOM_COST PVPP_KLM_VR
J 0
(-5750 2050);
DISPLAY 1.042553 (-5750 2050);
PAINT WHITE (-5750 2050);
DISPLAY INVISIBLE (-5750 2050);
FORCEPROP 1 LAST VOLTAGE 0.0V
J 0
(-5645 2057);
DISPLAY 0.340426 (-5645 2057);
PAINT SKYBLUE (-5645 2057);
DISPLAY INVISIBLE (-5645 2057);
FORCEPROP 1 LAST PATH I188
J 0
(-5525 2100);
DISPLAY 0.872340 (-5525 2100);
PAINT AQUA (-5525 2100);
DISPLAY INVISIBLE (-5525 2100);
FORCEPROP 2 LAST CDS_LIB mstr_symbols
J 0
(-5600 2100);
PAINT MONO (-5600 2100);
DISPLAY INVISIBLE (-5600 2100);
FORCEADD AGND_SCSI..1
(-5075 1950);
FORCEPROP 3 LASTPIN (-5075 2000) SIG_NAME AGND_PVPP_KLM\g
J 0
(-5065 2010);
DISPLAY 0.659574 (-5065 2010);
PAINT MONO (-5065 2010);
DISPLAY INVISIBLE (-5065 2010);
FORCEPROP 1 LAST HDL_POWER AGND_PVPP_KLM
J 1
(-5000 1875);
DISPLAY 0.617021 (-5000 1875);
PAINT GREEN (-5000 1875);
FORCEPROP 2 LAST ROOM PVPP_KLM_VR
J 0
(-5225 1900);
DISPLAY 1.042553 (-5225 1900);
PAINT GREEN (-5225 1900);
DISPLAY INVISIBLE (-5225 1900);
FORCEPROP 2 LAST BOM_COST PVPP_KLM_VR
J 0
(-5225 1900);
DISPLAY 1.042553 (-5225 1900);
PAINT WHITE (-5225 1900);
DISPLAY INVISIBLE (-5225 1900);
FORCEPROP 1 LAST BODY_TYPE PLUMBING
J 0
(-5120 1907);
DISPLAY 0.340426 (-5120 1907);
PAINT GREEN (-5120 1907);
DISPLAY INVISIBLE (-5120 1907);
FORCEPROP 1 LAST VOLTAGE 0.0V
J 0
(-5120 1907);
DISPLAY 0.340426 (-5120 1907);
PAINT SKYBLUE (-5120 1907);
DISPLAY INVISIBLE (-5120 1907);
FORCEPROP 1 LAST PATH I189
J 0
(-5000 1950);
DISPLAY 0.872340 (-5000 1950);
PAINT AQUA (-5000 1950);
DISPLAY INVISIBLE (-5000 1950);
FORCEPROP 2 LAST CDS_LIB mstr_symbols
J 0
(-5075 1950);
PAINT MONO (-5075 1950);
DISPLAY INVISIBLE (-5075 1950);
FORCEADD AGND_SCSI..1
(-4750 1350);
FORCEPROP 3 LASTPIN (-4750 1400) SIG_NAME AGND_PVPP_KLM\g
J 0
(-4740 1410);
DISPLAY 0.659574 (-4740 1410);
PAINT MONO (-4740 1410);
DISPLAY INVISIBLE (-4740 1410);
FORCEPROP 1 LAST HDL_POWER AGND_PVPP_KLM
J 1
(-4750 1300);
DISPLAY 0.617021 (-4750 1300);
PAINT GREEN (-4750 1300);
FORCEPROP 1 LAST PATH I190
J 0
(-4675 1350);
DISPLAY 0.872340 (-4675 1350);
PAINT AQUA (-4675 1350);
DISPLAY INVISIBLE (-4675 1350);
FORCEPROP 1 LAST BODY_TYPE PLUMBING
J 0
(-4795 1307);
DISPLAY 0.340426 (-4795 1307);
PAINT GREEN (-4795 1307);
DISPLAY INVISIBLE (-4795 1307);
FORCEPROP 2 LAST CDS_LIB mstr_symbols
J 0
(-4750 1350);
PAINT MONO (-4750 1350);
DISPLAY INVISIBLE (-4750 1350);
FORCEPROP 1 LAST VOLTAGE 0
J 0
(-4675 1375);
DISPLAY 1.021277 (-4675 1375);
PAINT SKYBLUE (-4675 1375);
DISPLAY INVISIBLE (-4675 1375);
FORCEADD AGND_SCSI..1
(-4375 1850);
FORCEPROP 3 LASTPIN (-4375 1900) SIG_NAME AGND_PVPP_KLM\g
J 0
(-4365 1910);
DISPLAY 0.659574 (-4365 1910);
PAINT MONO (-4365 1910);
DISPLAY INVISIBLE (-4365 1910);
FORCEPROP 1 LAST HDL_POWER AGND_PVPP_KLM
J 1
(-4300 1775);
DISPLAY 0.617021 (-4300 1775);
PAINT GREEN (-4300 1775);
FORCEPROP 2 LAST ROOM PVPP_KLM_VR
J 0
(-4525 1800);
DISPLAY 1.042553 (-4525 1800);
PAINT GREEN (-4525 1800);
DISPLAY INVISIBLE (-4525 1800);
FORCEPROP 1 LAST VOLTAGE 0.0V
J 0
(-4420 1807);
DISPLAY 0.340426 (-4420 1807);
PAINT SKYBLUE (-4420 1807);
DISPLAY INVISIBLE (-4420 1807);
FORCEPROP 2 LAST CDS_LIB mstr_symbols
J 0
(-4375 1850);
PAINT MONO (-4375 1850);
DISPLAY INVISIBLE (-4375 1850);
FORCEPROP 2 LAST BOM_COST PVPP_KLM_VR
J 0
(-4525 1800);
DISPLAY 1.042553 (-4525 1800);
PAINT WHITE (-4525 1800);
DISPLAY INVISIBLE (-4525 1800);
FORCEPROP 1 LAST BODY_TYPE PLUMBING
J 0
(-4420 1807);
DISPLAY 0.340426 (-4420 1807);
PAINT GREEN (-4420 1807);
DISPLAY INVISIBLE (-4420 1807);
FORCEPROP 1 LAST PATH I191
J 0
(-4300 1850);
DISPLAY 0.872340 (-4300 1850);
PAINT AQUA (-4300 1850);
DISPLAY INVISIBLE (-4300 1850);
FORCEADD GND..1
(-5175 3300);
FORCEPROP 3 LASTPIN (-5175 3350) SIG_NAME GND\g
J 0
(-5165 3360);
DISPLAY 0.659574 (-5165 3360);
PAINT MONO (-5165 3360);
DISPLAY INVISIBLE (-5165 3360);
FORCEPROP 2 LAST ROOM PVPP_KLM_VR
J 0
(-5750 3375);
DISPLAY 1.042553 (-5750 3375);
PAINT GREEN (-5750 3375);
DISPLAY INVISIBLE (-5750 3375);
FORCEPROP 2 LAST BOM_COST PVPP_KLM_VR
J 0
(-6025 3375);
DISPLAY 1.042553 (-6025 3375);
PAINT WHITE (-6025 3375);
DISPLAY INVISIBLE (-6025 3375);
FORCEPROP 1 LAST BODY_TYPE PLUMBING
J 0
(-5220 3257);
DISPLAY 0.340426 (-5220 3257);
PAINT GREEN (-5220 3257);
DISPLAY INVISIBLE (-5220 3257);
FORCEPROP 2 LAST CDS_LIB mstr_symbols
J 0
(-5175 3300);
PAINT MONO (-5175 3300);
DISPLAY INVISIBLE (-5175 3300);
FORCEPROP 1 LAST VOLTAGE 0
J 0
(-5175 3300);
PAINT SKYBLUE (-5175 3300);
DISPLAY INVISIBLE (-5175 3300);
FORCEPROP 1 LAST HDL_POWER GND
J 0
(-5175 3450);
DISPLAY 0.872340 (-5175 3450);
PAINT GREEN (-5175 3450);
DISPLAY INVISIBLE (-5175 3450);
FORCEPROP 1 LAST SIZE 1B
J 0
(-5100 3250);
DISPLAY 0.872340 (-5100 3250);
PAINT GREEN (-5100 3250);
DISPLAY INVISIBLE (-5100 3250);
FORCEPROP 1 LAST PATH I198
J 0
(-5100 3300);
DISPLAY 0.872340 (-5100 3300);
PAINT AQUA (-5100 3300);
DISPLAY INVISIBLE (-5100 3300);
FORCEADD CAP_A..1
(-5175 3525);
FORCEPROP 1 LASTPIN (-5175 3425) $PN 2
J 0
(-5165 3405);
DISPLAY 0.617021 (-5165 3405);
PAINT ORANGE (-5165 3405);
FORCEPROP 1 LASTPIN (-5175 3625) $PN 1
J 0
(-5165 3605);
DISPLAY 0.617021 (-5165 3605);
PAINT ORANGE (-5165 3605);
FORCEPROP 1 LAST MATERIAL X7R
J 0
(-5125 3425);
DISPLAY 0.617021 (-5125 3425);
PAINT SKYBLUE (-5125 3425);
FORCEPROP 1 LAST VOLTAGE 16V
J 0
(-5125 3525);
DISPLAY 0.617021 (-5125 3525);
PAINT SKYBLUE (-5125 3525);
FORCEPROP 1 LAST PACK_TYPE 0402V
J 0
(-5125 3325);
DISPLAY 0.617021 (-5125 3325);
PAINT SKYBLUE (-5125 3325);
FORCEPROP 1 LAST TOLERANCE 10%
J 0
(-5125 3475);
DISPLAY 0.617021 (-5125 3475);
PAINT SKYBLUE (-5125 3475);
FORCEPROP 1 LAST VALUE 0.1UF
J 0
(-5125 3575);
DISPLAY 0.617021 (-5125 3575);
PAINT SKYBLUE (-5125 3575);
FORCEPROP 1 LAST PART_NUMBER A36096-030
J 0
(-5125 3375);
DISPLAY 0.617021 (-5125 3375);
PAINT BLUE (-5125 3375);
FORCEPROP 1 LAST LOCATION C4A20
J 0
(-5125 3625);
DISPLAY 0.617021 (-5125 3625);
PAINT AQUA (-5125 3625);
FORCEPROP 2 LAST CDS_LIB dev_discrete
J 0
(-5175 3525);
PAINT ORANGE (-5175 3525);
DISPLAY INVISIBLE (-5175 3525);
FORCEPROP 2 LAST SEC 1
J 0
(-5125 3725);
PAINT MONO (-5125 3725);
DISPLAY INVISIBLE (-5125 3725);
FORCEPROP 2 LAST SEC_TYPE 0402V
J 0
(-5125 3725);
DISPLAY 1.021277 (-5125 3725);
PAINT ORANGE (-5125 3725);
DISPLAY INVISIBLE (-5125 3725);
FORCEPROP 2 LAST CDS_SEC 1
J 0
(-5125 3675);
PAINT ORANGE (-5125 3675);
DISPLAY INVISIBLE (-5125 3675);
FORCEPROP 2 LAST CDS_LOCATION C4A20
J 0
(-5125 3625);
DISPLAY 0.617021 (-5125 3625);
PAINT AQUA (-5125 3625);
DISPLAY INVISIBLE (-5125 3625);
FORCEPROP 1 LAST PATH I199
J 0
(-5125 3675);
DISPLAY 0.978723 (-5125 3675);
PAINT WHITE (-5125 3675);
DISPLAY INVISIBLE (-5125 3675);
FORCEADD AGND_SCSI..1
(-5400 2700);
FORCEPROP 3 LASTPIN (-5400 2750) SIG_NAME AGND_PVPP_KLM\g
J 0
(-5390 2760);
DISPLAY 0.659574 (-5390 2760);
PAINT MONO (-5390 2760);
DISPLAY INVISIBLE (-5390 2760);
FORCEPROP 1 LAST HDL_POWER AGND_PVPP_KLM
J 1
(-5325 2625);
DISPLAY 0.617021 (-5325 2625);
PAINT GREEN (-5325 2625);
FORCEPROP 2 LAST ROOM PVPP_KLM_VR
J 0
(-5550 2650);
DISPLAY 1.042553 (-5550 2650);
PAINT GREEN (-5550 2650);
DISPLAY INVISIBLE (-5550 2650);
FORCEPROP 1 LAST BODY_TYPE PLUMBING
J 0
(-5445 2657);
DISPLAY 0.340426 (-5445 2657);
PAINT GREEN (-5445 2657);
DISPLAY INVISIBLE (-5445 2657);
FORCEPROP 2 LAST CDS_LIB mstr_symbols
J 0
(-5400 2700);
PAINT MONO (-5400 2700);
DISPLAY INVISIBLE (-5400 2700);
FORCEPROP 2 LAST BOM_COST PVPP_KLM_VR
J 0
(-5550 2650);
DISPLAY 1.042553 (-5550 2650);
PAINT WHITE (-5550 2650);
DISPLAY INVISIBLE (-5550 2650);
FORCEPROP 1 LAST VOLTAGE 0.0V
J 0
(-5445 2657);
DISPLAY 0.340426 (-5445 2657);
PAINT SKYBLUE (-5445 2657);
DISPLAY INVISIBLE (-5445 2657);
FORCEPROP 1 LAST PATH I200
J 0
(-5325 2700);
DISPLAY 0.872340 (-5325 2700);
PAINT AQUA (-5325 2700);
DISPLAY INVISIBLE (-5325 2700);
FORCEADD RES..1
(-3350 975);
FORCEPROP 1 LASTPIN (-3450 975) $PN 1
J 0
(-3438 987);
DISPLAY 0.617021 (-3438 987);
PAINT ORANGE (-3438 987);
FORCEPROP 1 LAST WATTAGE 1/16W
J 2
(-3375 825);
DISPLAY 0.617021 (-3375 825);
PAINT SKYBLUE (-3375 825);
FORCEPROP 1 LAST VALUE 22.1
J 2
(-3375 875);
DISPLAY 0.617021 (-3375 875);
PAINT SKYBLUE (-3375 875);
FORCEPROP 1 LAST MATERIAL CHIP
J 0
(-3350 825);
DISPLAY 0.617021 (-3350 825);
PAINT SKYBLUE (-3350 825);
FORCEPROP 1 LAST TOLERANCE 1.0%
J 0
(-3350 875);
DISPLAY 0.617021 (-3350 875);
PAINT SKYBLUE (-3350 875);
FORCEPROP 1 LASTPIN (-3250 975) $PN 2
J 0
(-3288 987);
DISPLAY 0.617021 (-3288 987);
PAINT ORANGE (-3288 987);
FORCEPROP 1 LAST PART_NUMBER G21796-250
J 0
(-3400 1075);
DISPLAY 0.617021 (-3400 1075);
PAINT BLUE (-3400 1075);
FORCEPROP 1 LAST LOCATION R4B7
J 0
(-3400 1025);
DISPLAY 0.617021 (-3400 1025);
PAINT AQUA (-3400 1025);
FORCEPROP 1 LAST PACK_TYPE 0402
J 0
(-3100 825);
DISPLAY 0.617021 (-3100 825);
PAINT SKYBLUE (-3100 825);
FORCEPROP 2 LAST CDS_LIB mstr_discrete
J 0
(-3350 975);
PAINT MONO (-3350 975);
DISPLAY INVISIBLE (-3350 975);
FORCEPROP 2 LAST ROOM PVPP_KLM_VR
J 0
(-3400 1075);
DISPLAY 1.361702 (-3400 1075);
PAINT ORANGE (-3400 1075);
DISPLAY INVISIBLE (-3400 1075);
FORCEPROP 1 LAST PATH I201
J 0
(-3400 1125);
DISPLAY 0.978723 (-3400 1125);
PAINT WHITE (-3400 1125);
DISPLAY INVISIBLE (-3400 1125);
FORCEPROP 2 LAST CDS_LOCATION R4B7
J 0
(-3400 1025);
DISPLAY 0.617021 (-3400 1025);
PAINT AQUA (-3400 1025);
DISPLAY INVISIBLE (-3400 1025);
FORCEPROP 2 LAST SEC 1
J 0
(-3400 1175);
DISPLAY 0.680851 (-3400 1175);
PAINT MONO (-3400 1175);
DISPLAY INVISIBLE (-3400 1175);
FORCEPROP 2 LAST SEC_TYPE 0402
J 0
(-3400 1175);
DISPLAY 1.021277 (-3400 1175);
PAINT ORANGE (-3400 1175);
DISPLAY INVISIBLE (-3400 1175);
FORCEADD CAP..1
(-6875 4100);
FORCEPROP 1 LASTPIN (-6875 4000) $PN 2
J 0
(-6865 3980);
DISPLAY 0.617021 (-6865 3980);
PAINT ORANGE (-6865 3980);
FORCEPROP 1 LAST MATERIAL X6S
J 0
(-6825 4000);
DISPLAY 0.617021 (-6825 4000);
PAINT SKYBLUE (-6825 4000);
FORCEPROP 1 LAST PACK_TYPE 0805
J 0
(-6825 3900);
DISPLAY 0.617021 (-6825 3900);
PAINT SKYBLUE (-6825 3900);
FORCEPROP 1 LAST TOLERANCE 10%
J 0
(-6825 4050);
DISPLAY 0.617021 (-6825 4050);
PAINT SKYBLUE (-6825 4050);
FORCEPROP 1 LAST PART_NUMBER C95333-007
J 0
(-6825 3950);
DISPLAY 0.617021 (-6825 3950);
PAINT BLUE (-6825 3950);
FORCEPROP 1 LASTPIN (-6875 4200) $PN 1
J 0
(-6865 4180);
DISPLAY 0.617021 (-6865 4180);
PAINT ORANGE (-6865 4180);
FORCEPROP 1 LAST VOLTAGE 16V
J 0
(-6825 4100);
DISPLAY 0.617021 (-6825 4100);
PAINT SKYBLUE (-6825 4100);
FORCEPROP 1 LAST VALUE 10UF
J 0
(-6825 4150);
DISPLAY 0.617021 (-6825 4150);
PAINT SKYBLUE (-6825 4150);
FORCEPROP 1 LAST LOCATION C6L10
J 0
(-6825 4200);
DISPLAY 0.617021 (-6825 4200);
PAINT AQUA (-6825 4200);
FORCEPROP 2 LAST CDS_LIB mstr_discrete
J 0
(-6875 4100);
PAINT MONO (-6875 4100);
DISPLAY INVISIBLE (-6875 4100);
FORCEPROP 2 LAST CDS_LOCATION C6L10
J 0
(-6825 4200);
DISPLAY 0.617021 (-6825 4200);
PAINT AQUA (-6825 4200);
DISPLAY INVISIBLE (-6825 4200);
FORCEPROP 2 LAST SEC_TYPE 0805
J 0
(-6825 4300);
DISPLAY 1.021277 (-6825 4300);
PAINT ORANGE (-6825 4300);
DISPLAY INVISIBLE (-6825 4300);
FORCEPROP 2 LAST SEC 1
J 0
(-6825 4300);
DISPLAY 0.680851 (-6825 4300);
PAINT MONO (-6825 4300);
DISPLAY INVISIBLE (-6825 4300);
FORCEPROP 1 LAST PATH I202
J 0
(-6825 4250);
DISPLAY 0.978723 (-6825 4250);
PAINT WHITE (-6825 4250);
DISPLAY INVISIBLE (-6825 4250);
FORCEADD CAP..1
(-6375 4100);
FORCEPROP 1 LASTPIN (-6375 4000) $PN 2
J 0
(-6365 3980);
DISPLAY 0.617021 (-6365 3980);
PAINT ORANGE (-6365 3980);
FORCEPROP 1 LAST MATERIAL X6S
J 0
(-6325 4000);
DISPLAY 0.617021 (-6325 4000);
PAINT SKYBLUE (-6325 4000);
FORCEPROP 1 LAST PACK_TYPE 0805
J 0
(-6325 3900);
DISPLAY 0.617021 (-6325 3900);
PAINT SKYBLUE (-6325 3900);
FORCEPROP 1 LAST TOLERANCE 10%
J 0
(-6325 4050);
DISPLAY 0.617021 (-6325 4050);
PAINT SKYBLUE (-6325 4050);
FORCEPROP 1 LAST PART_NUMBER C95333-007
J 0
(-6325 3950);
DISPLAY 0.617021 (-6325 3950);
PAINT BLUE (-6325 3950);
FORCEPROP 1 LASTPIN (-6375 4200) $PN 1
J 0
(-6365 4180);
DISPLAY 0.617021 (-6365 4180);
PAINT ORANGE (-6365 4180);
FORCEPROP 1 LAST VOLTAGE 16V
J 0
(-6325 4100);
DISPLAY 0.617021 (-6325 4100);
PAINT SKYBLUE (-6325 4100);
FORCEPROP 1 LAST VALUE 10UF
J 0
(-6325 4150);
DISPLAY 0.617021 (-6325 4150);
PAINT SKYBLUE (-6325 4150);
FORCEPROP 1 LAST LOCATION C6M3
J 0
(-6325 4200);
DISPLAY 0.617021 (-6325 4200);
PAINT AQUA (-6325 4200);
FORCEPROP 2 LAST CDS_LIB mstr_discrete
J 0
(-6375 4100);
PAINT MONO (-6375 4100);
DISPLAY INVISIBLE (-6375 4100);
FORCEPROP 2 LAST CDS_LOCATION C6M3
J 0
(-6325 4200);
DISPLAY 0.617021 (-6325 4200);
PAINT AQUA (-6325 4200);
DISPLAY INVISIBLE (-6325 4200);
FORCEPROP 2 LAST SEC_TYPE 0805
J 0
(-6325 4300);
DISPLAY 1.021277 (-6325 4300);
PAINT ORANGE (-6325 4300);
DISPLAY INVISIBLE (-6325 4300);
FORCEPROP 2 LAST SEC 1
J 0
(-6325 4300);
DISPLAY 0.680851 (-6325 4300);
PAINT MONO (-6325 4300);
DISPLAY INVISIBLE (-6325 4300);
FORCEPROP 1 LAST PATH I203
J 0
(-6325 4250);
DISPLAY 0.978723 (-6325 4250);
PAINT WHITE (-6325 4250);
DISPLAY INVISIBLE (-6325 4250);
FORCEADD CAP..1
(-5925 4100);
FORCEPROP 1 LASTPIN (-5925 4000) $PN 2
J 0
(-5915 3980);
DISPLAY 0.617021 (-5915 3980);
PAINT ORANGE (-5915 3980);
FORCEPROP 1 LAST MATERIAL X6S
J 0
(-5875 4000);
DISPLAY 0.617021 (-5875 4000);
PAINT SKYBLUE (-5875 4000);
FORCEPROP 1 LAST PACK_TYPE 0805
J 0
(-5875 3900);
DISPLAY 0.617021 (-5875 3900);
PAINT SKYBLUE (-5875 3900);
FORCEPROP 1 LAST TOLERANCE 10%
J 0
(-5875 4050);
DISPLAY 0.617021 (-5875 4050);
PAINT SKYBLUE (-5875 4050);
FORCEPROP 1 LAST PART_NUMBER C95333-007
J 0
(-5875 3950);
DISPLAY 0.617021 (-5875 3950);
PAINT BLUE (-5875 3950);
FORCEPROP 1 LASTPIN (-5925 4200) $PN 1
J 0
(-5915 4180);
DISPLAY 0.617021 (-5915 4180);
PAINT ORANGE (-5915 4180);
FORCEPROP 1 LAST VOLTAGE 16V
J 0
(-5875 4100);
DISPLAY 0.617021 (-5875 4100);
PAINT SKYBLUE (-5875 4100);
FORCEPROP 1 LAST VALUE 10UF
J 0
(-5875 4150);
DISPLAY 0.617021 (-5875 4150);
PAINT SKYBLUE (-5875 4150);
FORCEPROP 1 LAST LOCATION C6M5
J 0
(-5875 4200);
DISPLAY 0.617021 (-5875 4200);
PAINT AQUA (-5875 4200);
FORCEPROP 2 LAST CDS_LIB mstr_discrete
J 0
(-5925 4100);
PAINT MONO (-5925 4100);
DISPLAY INVISIBLE (-5925 4100);
FORCEPROP 1 LAST PATH I204
J 0
(-5875 4250);
DISPLAY 0.978723 (-5875 4250);
PAINT WHITE (-5875 4250);
DISPLAY INVISIBLE (-5875 4250);
FORCEPROP 2 LAST CDS_LOCATION C6M5
J 0
(-5875 4200);
DISPLAY 0.617021 (-5875 4200);
PAINT AQUA (-5875 4200);
DISPLAY INVISIBLE (-5875 4200);
FORCEPROP 2 LAST SEC 1
J 0
(-5875 4300);
DISPLAY 0.680851 (-5875 4300);
PAINT MONO (-5875 4300);
DISPLAY INVISIBLE (-5875 4300);
FORCEPROP 2 LAST SEC_TYPE 0805
J 0
(-5875 4300);
DISPLAY 1.021277 (-5875 4300);
PAINT ORANGE (-5875 4300);
DISPLAY INVISIBLE (-5875 4300);
FORCEADD CAP..1
(-5475 4100);
FORCEPROP 1 LASTPIN (-5475 4000) $PN 2
J 0
(-5465 3980);
DISPLAY 0.617021 (-5465 3980);
PAINT ORANGE (-5465 3980);
FORCEPROP 1 LAST MATERIAL X6S
J 0
(-5425 4000);
DISPLAY 0.617021 (-5425 4000);
PAINT SKYBLUE (-5425 4000);
FORCEPROP 1 LAST PACK_TYPE 0805
J 0
(-5425 3900);
DISPLAY 0.617021 (-5425 3900);
PAINT SKYBLUE (-5425 3900);
FORCEPROP 1 LAST TOLERANCE 10%
J 0
(-5425 4050);
DISPLAY 0.617021 (-5425 4050);
PAINT SKYBLUE (-5425 4050);
FORCEPROP 1 LAST PART_NUMBER C95333-007
J 0
(-5425 3950);
DISPLAY 0.617021 (-5425 3950);
PAINT BLUE (-5425 3950);
FORCEPROP 1 LASTPIN (-5475 4200) $PN 1
J 0
(-5465 4180);
DISPLAY 0.617021 (-5465 4180);
PAINT ORANGE (-5465 4180);
FORCEPROP 1 LAST VOLTAGE 16V
J 0
(-5425 4100);
DISPLAY 0.617021 (-5425 4100);
PAINT SKYBLUE (-5425 4100);
FORCEPROP 1 LAST VALUE 10UF
J 0
(-5425 4150);
DISPLAY 0.617021 (-5425 4150);
PAINT SKYBLUE (-5425 4150);
FORCEPROP 1 LAST LOCATION C4A19
J 0
(-5425 4200);
DISPLAY 0.617021 (-5425 4200);
PAINT AQUA (-5425 4200);
FORCEPROP 2 LAST CDS_LIB mstr_discrete
J 0
(-5475 4100);
PAINT MONO (-5475 4100);
DISPLAY INVISIBLE (-5475 4100);
FORCEPROP 2 LAST CDS_LOCATION C4A19
J 0
(-5425 4200);
DISPLAY 0.617021 (-5425 4200);
PAINT AQUA (-5425 4200);
DISPLAY INVISIBLE (-5425 4200);
FORCEPROP 2 LAST SEC_TYPE 0805
J 0
(-5425 4300);
DISPLAY 1.021277 (-5425 4300);
PAINT ORANGE (-5425 4300);
DISPLAY INVISIBLE (-5425 4300);
FORCEPROP 2 LAST SEC 1
J 0
(-5425 4300);
DISPLAY 0.680851 (-5425 4300);
PAINT MONO (-5425 4300);
DISPLAY INVISIBLE (-5425 4300);
FORCEPROP 1 LAST PATH I205
J 0
(-5425 4250);
DISPLAY 0.978723 (-5425 4250);
PAINT WHITE (-5425 4250);
DISPLAY INVISIBLE (-5425 4250);
FORCEADD GND..1
(-6875 3900);
FORCEPROP 3 LASTPIN (-6875 3950) SIG_NAME GND\g
J 0
(-6865 3960);
DISPLAY 0.659574 (-6865 3960);
PAINT MONO (-6865 3960);
DISPLAY INVISIBLE (-6865 3960);
FORCEPROP 2 LAST BOM_COST PVPP_KLM_VR
J 0
(-7725 3975);
DISPLAY 1.042553 (-7725 3975);
PAINT WHITE (-7725 3975);
DISPLAY INVISIBLE (-7725 3975);
FORCEPROP 2 LAST ROOM PVPP_KLM_VR
J 0
(-7450 3975);
DISPLAY 1.042553 (-7450 3975);
PAINT GREEN (-7450 3975);
DISPLAY INVISIBLE (-7450 3975);
FORCEPROP 1 LAST BODY_TYPE PLUMBING
J 0
(-6920 3857);
DISPLAY 0.340426 (-6920 3857);
PAINT GREEN (-6920 3857);
DISPLAY INVISIBLE (-6920 3857);
FORCEPROP 1 LAST VOLTAGE 0
J 0
(-6875 3900);
PAINT SKYBLUE (-6875 3900);
DISPLAY INVISIBLE (-6875 3900);
FORCEPROP 2 LAST CDS_LIB mstr_symbols
J 0
(-6875 3900);
PAINT MONO (-6875 3900);
DISPLAY INVISIBLE (-6875 3900);
FORCEPROP 1 LAST SIZE 1B
J 0
(-6800 3850);
DISPLAY 0.872340 (-6800 3850);
PAINT GREEN (-6800 3850);
DISPLAY INVISIBLE (-6800 3850);
FORCEPROP 1 LAST PATH I206
J 0
(-6800 3900);
DISPLAY 0.872340 (-6800 3900);
PAINT AQUA (-6800 3900);
DISPLAY INVISIBLE (-6800 3900);
FORCEPROP 1 LAST HDL_POWER GND
J 0
(-6875 4050);
DISPLAY 0.872340 (-6875 4050);
PAINT GREEN (-6875 4050);
DISPLAY INVISIBLE (-6875 4050);
FORCEADD GND..1
(-6375 3900);
FORCEPROP 3 LASTPIN (-6375 3950) SIG_NAME GND\g
J 0
(-6365 3960);
DISPLAY 0.659574 (-6365 3960);
PAINT MONO (-6365 3960);
DISPLAY INVISIBLE (-6365 3960);
FORCEPROP 2 LAST BOM_COST PVPP_KLM_VR
J 0
(-7225 3975);
DISPLAY 1.042553 (-7225 3975);
PAINT WHITE (-7225 3975);
DISPLAY INVISIBLE (-7225 3975);
FORCEPROP 2 LAST ROOM PVPP_KLM_VR
J 0
(-6950 3975);
DISPLAY 1.042553 (-6950 3975);
PAINT GREEN (-6950 3975);
DISPLAY INVISIBLE (-6950 3975);
FORCEPROP 1 LAST BODY_TYPE PLUMBING
J 0
(-6420 3857);
DISPLAY 0.340426 (-6420 3857);
PAINT GREEN (-6420 3857);
DISPLAY INVISIBLE (-6420 3857);
FORCEPROP 1 LAST VOLTAGE 0
J 0
(-6375 3900);
PAINT SKYBLUE (-6375 3900);
DISPLAY INVISIBLE (-6375 3900);
FORCEPROP 2 LAST CDS_LIB mstr_symbols
J 0
(-6375 3900);
PAINT MONO (-6375 3900);
DISPLAY INVISIBLE (-6375 3900);
FORCEPROP 1 LAST SIZE 1B
J 0
(-6300 3850);
DISPLAY 0.872340 (-6300 3850);
PAINT GREEN (-6300 3850);
DISPLAY INVISIBLE (-6300 3850);
FORCEPROP 1 LAST PATH I207
J 0
(-6300 3900);
DISPLAY 0.872340 (-6300 3900);
PAINT AQUA (-6300 3900);
DISPLAY INVISIBLE (-6300 3900);
FORCEPROP 1 LAST HDL_POWER GND
J 0
(-6375 4050);
DISPLAY 0.872340 (-6375 4050);
PAINT GREEN (-6375 4050);
DISPLAY INVISIBLE (-6375 4050);
FORCEADD GND..1
(-5925 3900);
FORCEPROP 3 LASTPIN (-5925 3950) SIG_NAME GND\g
J 0
(-5915 3960);
DISPLAY 0.659574 (-5915 3960);
PAINT MONO (-5915 3960);
DISPLAY INVISIBLE (-5915 3960);
FORCEPROP 2 LAST BOM_COST PVPP_KLM_VR
J 0
(-6775 3975);
DISPLAY 1.042553 (-6775 3975);
PAINT WHITE (-6775 3975);
DISPLAY INVISIBLE (-6775 3975);
FORCEPROP 2 LAST ROOM PVPP_KLM_VR
J 0
(-6500 3975);
DISPLAY 1.042553 (-6500 3975);
PAINT GREEN (-6500 3975);
DISPLAY INVISIBLE (-6500 3975);
FORCEPROP 1 LAST VOLTAGE 0
J 0
(-5925 3900);
PAINT SKYBLUE (-5925 3900);
DISPLAY INVISIBLE (-5925 3900);
FORCEPROP 2 LAST CDS_LIB mstr_symbols
J 0
(-5925 3900);
PAINT MONO (-5925 3900);
DISPLAY INVISIBLE (-5925 3900);
FORCEPROP 1 LAST BODY_TYPE PLUMBING
J 0
(-5970 3857);
DISPLAY 0.340426 (-5970 3857);
PAINT GREEN (-5970 3857);
DISPLAY INVISIBLE (-5970 3857);
FORCEPROP 1 LAST HDL_POWER GND
J 0
(-5925 4050);
DISPLAY 0.872340 (-5925 4050);
PAINT GREEN (-5925 4050);
DISPLAY INVISIBLE (-5925 4050);
FORCEPROP 1 LAST PATH I208
J 0
(-5850 3900);
DISPLAY 0.872340 (-5850 3900);
PAINT AQUA (-5850 3900);
DISPLAY INVISIBLE (-5850 3900);
FORCEPROP 1 LAST SIZE 1B
J 0
(-5850 3850);
DISPLAY 0.872340 (-5850 3850);
PAINT GREEN (-5850 3850);
DISPLAY INVISIBLE (-5850 3850);
FORCEADD GND..1
(-5475 3900);
FORCEPROP 3 LASTPIN (-5475 3950) SIG_NAME GND\g
J 0
(-5465 3960);
DISPLAY 0.659574 (-5465 3960);
PAINT MONO (-5465 3960);
DISPLAY INVISIBLE (-5465 3960);
FORCEPROP 2 LAST BOM_COST PVPP_KLM_VR
J 0
(-6325 3975);
DISPLAY 1.042553 (-6325 3975);
PAINT WHITE (-6325 3975);
DISPLAY INVISIBLE (-6325 3975);
FORCEPROP 2 LAST ROOM PVPP_KLM_VR
J 0
(-6050 3975);
DISPLAY 1.042553 (-6050 3975);
PAINT GREEN (-6050 3975);
DISPLAY INVISIBLE (-6050 3975);
FORCEPROP 1 LAST BODY_TYPE PLUMBING
J 0
(-5520 3857);
DISPLAY 0.340426 (-5520 3857);
PAINT GREEN (-5520 3857);
DISPLAY INVISIBLE (-5520 3857);
FORCEPROP 1 LAST VOLTAGE 0
J 0
(-5475 3900);
PAINT SKYBLUE (-5475 3900);
DISPLAY INVISIBLE (-5475 3900);
FORCEPROP 1 LAST PATH I209
J 0
(-5400 3900);
DISPLAY 0.872340 (-5400 3900);
PAINT AQUA (-5400 3900);
DISPLAY INVISIBLE (-5400 3900);
FORCEPROP 2 LAST CDS_LIB mstr_symbols
J 0
(-5475 3900);
PAINT MONO (-5475 3900);
DISPLAY INVISIBLE (-5475 3900);
FORCEPROP 1 LAST SIZE 1B
J 0
(-5400 3850);
DISPLAY 0.872340 (-5400 3850);
PAINT GREEN (-5400 3850);
DISPLAY INVISIBLE (-5400 3850);
FORCEPROP 1 LAST HDL_POWER GND
J 0
(-5475 4050);
DISPLAY 0.872340 (-5475 4050);
PAINT GREEN (-5475 4050);
DISPLAY INVISIBLE (-5475 4050);
FORCEADD CAPP..1
(-1425 3675);
FORCEPROP 1 LAST PACK_TYPE 7343
J 0
(-1375 3525);
DISPLAY 0.617021 (-1375 3525);
PAINT SKYBLUE (-1375 3525);
FORCEPROP 1 LAST PART_NUMBER 724613-067
J 0
(-1375 3475);
DISPLAY 0.617021 (-1375 3475);
PAINT BLUE (-1375 3475);
FORCEPROP 1 LASTPIN (-1425 3575) $PN 2
J 0
(-1415 3560);
DISPLAY 0.617021 (-1415 3560);
PAINT ORANGE (-1415 3560);
FORCEPROP 1 LAST MATERIAL POSCAP
J 0
(-1375 3575);
DISPLAY 0.617021 (-1375 3575);
PAINT SKYBLUE (-1375 3575);
FORCEPROP 1 LASTPIN (-1425 3775) $PN 1
J 0
(-1415 3760);
DISPLAY 0.617021 (-1415 3760);
PAINT ORANGE (-1415 3760);
FORCEPROP 1 LAST VOLTAGE 4V
J 0
(-1375 3625);
DISPLAY 0.617021 (-1375 3625);
PAINT SKYBLUE (-1375 3625);
FORCEPROP 1 LAST TOLERANCE 20%
J 0
(-1375 3675);
DISPLAY 0.617021 (-1375 3675);
PAINT SKYBLUE (-1375 3675);
FORCEPROP 1 LAST VALUE 220UF
J 0
(-1375 3725);
DISPLAY 0.617021 (-1375 3725);
PAINT SKYBLUE (-1375 3725);
FORCEPROP 1 LAST LOCATION C6L8
J 0
(-1375 3775);
DISPLAY 0.617021 (-1375 3775);
PAINT AQUA (-1375 3775);
FORCEPROP 2 LAST CDS_LIB mstr_discrete
J 0
(-1425 3675);
PAINT ORANGE (-1425 3675);
DISPLAY INVISIBLE (-1425 3675);
FORCEPROP 2 LAST CDS_LOCATION C6L8
J 0
(-1375 3775);
DISPLAY 0.617021 (-1375 3775);
PAINT AQUA (-1375 3775);
DISPLAY INVISIBLE (-1375 3775);
FORCEPROP 1 LAST PATH I210
J 0
(-1375 3825);
DISPLAY 0.978723 (-1375 3825);
PAINT ORANGE (-1375 3825);
DISPLAY INVISIBLE (-1375 3825);
FORCEPROP 2 LAST SEC 1
J 0
(-1375 3875);
DISPLAY 0.680851 (-1375 3875);
PAINT MONO (-1375 3875);
DISPLAY INVISIBLE (-1375 3875);
FORCEPROP 2 LAST SEC_TYPE 7343
J 0
(-1375 3875);
DISPLAY 1.021277 (-1375 3875);
PAINT ORANGE (-1375 3875);
DISPLAY INVISIBLE (-1375 3875);
FORCEADD CAP..2
R 2
(-2850 2450);
FORCEPROP 1 LAST VOLTAGE 50V
J 2
(-2850 2325);
DISPLAY 0.617021 (-2850 2325);
PAINT SKYBLUE (-2850 2325);
FORCEPROP 1 LAST MATERIAL X7R
J 2
(-2825 2275);
DISPLAY 0.617021 (-2825 2275);
PAINT SKYBLUE (-2825 2275);
FORCEPROP 1 LASTPIN (-2950 2450) $PN 2
J 2
(-2935 2465);
DISPLAY 0.617021 (-2935 2465);
PAINT ORANGE (-2935 2465);
FORCEPROP 1 LAST LOCATION C4B9
J 1
(-2850 2525);
DISPLAY 0.617021 (-2850 2525);
PAINT AQUA (-2850 2525);
FORCEPROP 1 LAST TOLERANCE 10%
J 0
(-2825 2275);
DISPLAY 0.617021 (-2825 2275);
PAINT SKYBLUE (-2825 2275);
FORCEPROP 1 LAST VALUE 2200PF
J 0
(-2825 2325);
DISPLAY 0.617021 (-2825 2325);
PAINT SKYBLUE (-2825 2325);
FORCEPROP 1 LAST PART_NUMBER A36096-075
J 1
(-2800 2375);
DISPLAY 0.617021 (-2800 2375);
PAINT BLUE (-2800 2375);
FORCEPROP 1 LAST PACK_TYPE 0402LF
J 1
(-2850 2225);
DISPLAY 0.617021 (-2850 2225);
PAINT SKYBLUE (-2850 2225);
FORCEPROP 1 LASTPIN (-2750 2450) $PN 1
J 2
(-2740 2465);
DISPLAY 0.617021 (-2740 2465);
PAINT ORANGE (-2740 2465);
FORCEPROP 2 LAST CDS_LIB mstr_discrete
J 0
(-2850 2450);
PAINT ORANGE (-2850 2450);
DISPLAY INVISIBLE (-2850 2450);
FORCEPROP 2 LAST CDS_LOCATION C4B9
J 1
(-2850 2525);
DISPLAY 0.617021 (-2850 2525);
PAINT AQUA (-2850 2525);
DISPLAY INVISIBLE (-2850 2525);
FORCEPROP 2 LAST SEC_TYPE 0402LF
J 0
(-2850 2700);
DISPLAY 1.021277 (-2850 2700);
PAINT ORANGE (-2850 2700);
DISPLAY INVISIBLE (-2850 2700);
FORCEPROP 2 LAST BOM_COST PVPP_KLM_VR
J 0
(-2895 2610);
DISPLAY 1.042553 (-2895 2610);
PAINT WHITE (-2895 2610);
DISPLAY INVISIBLE (-2895 2610);
FORCEPROP 2 LAST REUSE_ID 27
J 0
(-2850 2700);
DISPLAY 1.042553 (-2850 2700);
PAINT ORANGE (-2850 2700);
DISPLAY INVISIBLE (-2850 2700);
FORCEPROP 2 LAST SEC 1
J 0
(-2850 2700);
DISPLAY 0.680851 (-2850 2700);
PAINT MONO (-2850 2700);
DISPLAY INVISIBLE (-2850 2700);
FORCEPROP 1 LAST PATH I211
J 2
(-2850 2650);
DISPLAY 0.978723 (-2850 2650);
PAINT WHITE (-2850 2650);
DISPLAY INVISIBLE (-2850 2650);
FORCEPROP 2 LAST ROOM PVPP_KLM_VR
J 2
(-2850 2575);
DISPLAY 0.765957 (-2850 2575);
PAINT GREEN (-2850 2575);
DISPLAY INVISIBLE (-2850 2575);
FORCEADD CAP..2
R 2
(-2425 2825);
FORCEPROP 1 LAST PART_NUMBER A36095-026
J 1
(-2725 2725);
DISPLAY 0.617021 (-2725 2725);
PAINT BLUE (-2725 2725);
FORCEPROP 1 LAST PACK_TYPE 0402LF
J 1
(-2400 2675);
DISPLAY 0.617021 (-2400 2675);
PAINT SKYBLUE (-2400 2675);
FORCEPROP 1 LAST VOLTAGE 50V
J 2
(-2425 2725);
DISPLAY 0.617021 (-2425 2725);
PAINT SKYBLUE (-2425 2725);
FORCEPROP 1 LAST LOCATION C4B4
J 1
(-2425 2875);
DISPLAY 0.617021 (-2425 2875);
PAINT AQUA (-2425 2875);
FORCEPROP 1 LASTPIN (-2525 2825) $PN 2
J 2
(-2510 2840);
DISPLAY 0.617021 (-2510 2840);
PAINT ORANGE (-2510 2840);
FORCEPROP 1 LASTPIN (-2325 2825) $PN 1
J 2
(-2315 2840);
DISPLAY 0.617021 (-2315 2840);
PAINT ORANGE (-2315 2840);
FORCEPROP 1 LAST VALUE 100.0PF
J 0
(-2425 2725);
DISPLAY 0.617021 (-2425 2725);
PAINT SKYBLUE (-2425 2725);
FORCEPROP 1 LAST MATERIAL COG
J 2
(-2050 2725);
DISPLAY 0.617021 (-2050 2725);
PAINT SKYBLUE (-2050 2725);
FORCEPROP 1 LAST TOLERANCE 5%
J 0
(-2050 2725);
DISPLAY 0.617021 (-2050 2725);
PAINT SKYBLUE (-2050 2725);
FORCEPROP 2 LAST ROOM PVPP_KLM_VR
J 2
(-2425 2950);
DISPLAY 0.765957 (-2425 2950);
PAINT GREEN (-2425 2950);
DISPLAY INVISIBLE (-2425 2950);
FORCEPROP 1 LAST PATH I212
J 2
(-2425 3025);
DISPLAY 0.978723 (-2425 3025);
PAINT WHITE (-2425 3025);
DISPLAY INVISIBLE (-2425 3025);
FORCEPROP 2 LAST CDS_LOCATION C4B4
J 1
(-2425 2875);
DISPLAY 0.617021 (-2425 2875);
PAINT AQUA (-2425 2875);
DISPLAY INVISIBLE (-2425 2875);
FORCEPROP 2 LAST BOM_COST PVPP_KLM_VR
J 0
(-2470 2985);
DISPLAY 1.042553 (-2470 2985);
PAINT WHITE (-2470 2985);
DISPLAY INVISIBLE (-2470 2985);
FORCEPROP 2 LAST CDS_LIB mstr_discrete
J 0
(-2425 2825);
PAINT ORANGE (-2425 2825);
DISPLAY INVISIBLE (-2425 2825);
FORCEPROP 2 LAST SEC 1
J 0
(-2425 3075);
DISPLAY 0.680851 (-2425 3075);
PAINT MONO (-2425 3075);
DISPLAY INVISIBLE (-2425 3075);
FORCEPROP 2 LAST REUSE_ID 27
J 0
(-2425 3075);
DISPLAY 1.042553 (-2425 3075);
PAINT ORANGE (-2425 3075);
DISPLAY INVISIBLE (-2425 3075);
FORCEPROP 2 LAST SEC_TYPE 0402LF
J 0
(-2425 3075);
DISPLAY 1.021277 (-2425 3075);
PAINT ORANGE (-2425 3075);
DISPLAY INVISIBLE (-2425 3075);
FORCEADD RES..1
(-2150 2450);
FORCEPROP 1 LAST WATTAGE 1/16W
J 2
(-2175 2275);
DISPLAY 0.617021 (-2175 2275);
PAINT SKYBLUE (-2175 2275);
FORCEPROP 1 LAST VALUE 7.87K
J 2
(-2250 2325);
DISPLAY 0.617021 (-2250 2325);
PAINT SKYBLUE (-2250 2325);
FORCEPROP 1 LASTPIN (-2250 2450) $PN 1
J 0
(-2238 2462);
DISPLAY 0.617021 (-2238 2462);
PAINT ORANGE (-2238 2462);
FORCEPROP 1 LAST TOLERANCE 1.0%
J 0
(-2200 2325);
DISPLAY 0.617021 (-2200 2325);
PAINT SKYBLUE (-2200 2325);
FORCEPROP 1 LAST LOCATION R4B8
J 0
(-2200 2500);
DISPLAY 0.617021 (-2200 2500);
PAINT AQUA (-2200 2500);
FORCEPROP 1 LASTPIN (-2050 2450) $PN 2
J 0
(-2088 2462);
DISPLAY 0.617021 (-2088 2462);
PAINT ORANGE (-2088 2462);
FORCEPROP 1 LAST MATERIAL CHIP
J 0
(-2150 2275);
DISPLAY 0.617021 (-2150 2275);
PAINT SKYBLUE (-2150 2275);
FORCEPROP 1 LAST PACK_TYPE 0402
J 0
(-2100 2325);
DISPLAY 0.617021 (-2100 2325);
PAINT SKYBLUE (-2100 2325);
FORCEPROP 1 LAST PART_NUMBER G21796-242
J 0
(-2300 2375);
DISPLAY 0.617021 (-2300 2375);
PAINT BLUE (-2300 2375);
FORCEPROP 2 LAST CDS_LOCATION R4B8
J 0
(-2200 2500);
DISPLAY 0.617021 (-2200 2500);
PAINT AQUA (-2200 2500);
DISPLAY INVISIBLE (-2200 2500);
FORCEPROP 2 LAST BOM_COST PVPP_KLM_VR
J 0
(-2150 2450);
PAINT WHITE (-2150 2450);
DISPLAY INVISIBLE (-2150 2450);
FORCEPROP 2 LAST CDS_LIB mstr_discrete
J 0
(-2150 2450);
PAINT MONO (-2150 2450);
DISPLAY INVISIBLE (-2150 2450);
FORCEPROP 2 LAST ROOM PVPP_KLM_VR
J 0
(-2150 2450);
PAINT GREEN (-2150 2450);
DISPLAY INVISIBLE (-2150 2450);
FORCEPROP 0 LAST SEC 1
J 0
(-2200 2550);
PAINT MONO (-2200 2550);
DISPLAY INVISIBLE (-2200 2550);
FORCEPROP 2 LAST SEC_TYPE 0402
J 0
(-2200 2650);
DISPLAY 1.021277 (-2200 2650);
PAINT ORANGE (-2200 2650);
DISPLAY INVISIBLE (-2200 2650);
FORCEPROP 2 LAST REUSE_ID 13
J 0
(-2200 2650);
DISPLAY 1.042553 (-2200 2650);
PAINT ORANGE (-2200 2650);
DISPLAY INVISIBLE (-2200 2650);
FORCEPROP 1 LAST PATH I213
J 0
(-2200 2600);
DISPLAY 0.978723 (-2200 2600);
PAINT WHITE (-2200 2600);
DISPLAY INVISIBLE (-2200 2600);
FORCEADD RES..1
R 5
(-1350 2925);
FORCEPROP 1 LASTPIN (-1350 2825) $PN 2
J 0
(-1338 2863);
DISPLAY 0.617021 (-1338 2863);
PAINT ORANGE (-1338 2863);
FORCEPROP 1 LASTPIN (-1350 3025) $PN 1
J 0
(-1338 3013);
DISPLAY 0.617021 (-1338 3013);
PAINT ORANGE (-1338 3013);
FORCEPROP 1 LAST WATTAGE 1/16W
J 0
(-1325 2925);
DISPLAY 0.617021 (-1325 2925);
PAINT SKYBLUE (-1325 2925);
FORCEPROP 1 LAST MATERIAL CHIP
J 0
(-1325 2825);
DISPLAY 0.617021 (-1325 2825);
PAINT SKYBLUE (-1325 2825);
FORCEPROP 1 LAST PACK_TYPE 0402
J 0
(-1325 2775);
DISPLAY 0.617021 (-1325 2775);
PAINT SKYBLUE (-1325 2775);
FORCEPROP 1 LAST TOLERANCE 5%
J 0
(-1325 2875);
DISPLAY 0.617021 (-1325 2875);
PAINT SKYBLUE (-1325 2875);
FORCEPROP 1 LAST VALUE 0.0
J 0
(-1300 2975);
DISPLAY 0.617021 (-1300 2975);
PAINT SKYBLUE (-1300 2975);
FORCEPROP 1 LAST PART_NUMBER G21497-005
J 0
(-1325 2725);
DISPLAY 0.617021 (-1325 2725);
PAINT BLUE (-1325 2725);
FORCEPROP 1 LAST LOCATION R4B3
J 0
(-1250 2875);
DISPLAY 0.617021 (-1250 2875);
PAINT AQUA (-1250 2875);
FORCEPROP 2 LAST CDS_LIB mstr_discrete
J 0
(-1350 2925);
PAINT ORANGE (-1350 2925);
DISPLAY INVISIBLE (-1350 2925);
FORCEPROP 2 LAST ROOM PVPP_KLM_VR
R 3
J 0
(-1200 2975);
DISPLAY 1.659574 (-1200 2975);
PAINT GREEN (-1200 2975);
DISPLAY INVISIBLE (-1200 2975);
FORCEPROP 1 LAST PATH I214
R 3
J 0
(-1200 2975);
DISPLAY 0.978723 (-1200 2975);
PAINT WHITE (-1200 2975);
DISPLAY INVISIBLE (-1200 2975);
FORCEPROP 2 LAST CDS_LOCATION R4B3
J 0
(-1250 2875);
DISPLAY 0.617021 (-1250 2875);
PAINT AQUA (-1250 2875);
DISPLAY INVISIBLE (-1250 2875);
FORCEPROP 0 LAST SPOF TRUE
J 0
(-1300 3075);
DISPLAY 1.021277 (-1300 3075);
PAINT ORANGE (-1300 3075);
DISPLAY INVISIBLE (-1300 3075);
FORCEPROP 2 LAST SEC_TYPE 0402
J 0
(-1275 3075);
DISPLAY 1.021277 (-1275 3075);
PAINT ORANGE (-1275 3075);
DISPLAY INVISIBLE (-1275 3075);
FORCEPROP 2 LAST SEC 1
J 0
(-1275 3075);
DISPLAY 0.680851 (-1275 3075);
PAINT MONO (-1275 3075);
DISPLAY INVISIBLE (-1275 3075);
FORCEADD RES..2
(-1350 2175);
FORCEPROP 1 LAST PART_NUMBER G21796-040
J 0
(-1335 2000);
DISPLAY 0.617021 (-1335 2000);
PAINT BLUE (-1335 2000);
FORCEPROP 1 LASTPIN (-1350 2075) $PN 2
J 0
(-1345 2085);
DISPLAY 0.617021 (-1345 2085);
PAINT WHITE (-1345 2085);
FORCEPROP 1 LASTPIN (-1350 2275) $PN 1
J 0
(-1345 2237);
DISPLAY 0.617021 (-1345 2237);
PAINT WHITE (-1345 2237);
FORCEPROP 1 LAST WATTAGE 1/16W
J 0
(-1310 2150);
DISPLAY 0.617021 (-1310 2150);
PAINT SKYBLUE (-1310 2150);
FORCEPROP 1 LAST MATERIAL CHIP
J 0
(-1310 2050);
DISPLAY 0.617021 (-1310 2050);
PAINT SKYBLUE (-1310 2050);
FORCEPROP 1 LAST PACK_TYPE 0402
J 0
(-1310 2100);
DISPLAY 0.617021 (-1310 2100);
PAINT SKYBLUE (-1310 2100);
FORCEPROP 1 LAST TOLERANCE 1%
J 0
(-1305 2200);
DISPLAY 0.617021 (-1305 2200);
PAINT SKYBLUE (-1305 2200);
FORCEPROP 1 LAST VALUE 20.0K
J 0
(-1305 2250);
DISPLAY 0.617021 (-1305 2250);
PAINT SKYBLUE (-1305 2250);
FORCEPROP 1 LAST LOCATION R4B5
J 0
(-1305 2300);
DISPLAY 0.617021 (-1305 2300);
PAINT AQUA (-1305 2300);
FORCEPROP 2 LAST CDS_LIB mstr_discrete
J 0
(-1350 2175);
PAINT MONO (-1350 2175);
DISPLAY INVISIBLE (-1350 2175);
FORCEPROP 2 LAST CDS_LOCATION R4B5
J 0
(-1305 2300);
DISPLAY 0.617021 (-1305 2300);
PAINT AQUA (-1305 2300);
DISPLAY INVISIBLE (-1305 2300);
FORCEPROP 2 LAST ROOM PVPP_KLM_VR
J 0
(-1305 2330);
PAINT GREEN (-1305 2330);
DISPLAY INVISIBLE (-1305 2330);
FORCEPROP 2 LAST BOM_COST PVPP_KLM_VR
J 0
(-1305 2355);
DISPLAY 1.042553 (-1305 2355);
PAINT WHITE (-1305 2355);
DISPLAY INVISIBLE (-1305 2355);
FORCEPROP 0 LAST SPOF TRUE
J 0
(-1300 2400);
DISPLAY 1.021277 (-1300 2400);
PAINT ORANGE (-1300 2400);
DISPLAY INVISIBLE (-1300 2400);
FORCEPROP 2 LAST CDS_SEC 1
J 0
(-1300 2400);
DISPLAY 1.042553 (-1300 2400);
PAINT ORANGE (-1300 2400);
DISPLAY INVISIBLE (-1300 2400);
FORCEPROP 2 LAST REUSE_ID 9
J 0
(-1300 2400);
DISPLAY 1.042553 (-1300 2400);
PAINT ORANGE (-1300 2400);
DISPLAY INVISIBLE (-1300 2400);
FORCEPROP 1 LAST PATH I215
J 0
(-1300 2350);
DISPLAY 0.978723 (-1300 2350);
PAINT WHITE (-1300 2350);
DISPLAY INVISIBLE (-1300 2350);
FORCEPROP 2 LAST $SEC 1
J 0
(-1300 2400);
DISPLAY 0.680851 (-1300 2400);
PAINT MONO (-1300 2400);
DISPLAY INVISIBLE (-1300 2400);
FORCEADD RES..2
(-1350 1550);
FORCEPROP 1 LASTPIN (-1350 1450) $PN 2
J 0
(-1345 1460);
DISPLAY 0.617021 (-1345 1460);
PAINT WHITE (-1345 1460);
FORCEPROP 1 LAST MATERIAL CHIP
J 0
(-1310 1475);
DISPLAY 0.617021 (-1310 1475);
PAINT SKYBLUE (-1310 1475);
FORCEPROP 1 LAST PACK_TYPE 0402
J 0
(-1310 1375);
DISPLAY 0.617021 (-1310 1375);
PAINT SKYBLUE (-1310 1375);
FORCEPROP 1 LAST WATTAGE 1/16W
J 0
(-1310 1525);
DISPLAY 0.617021 (-1310 1525);
PAINT SKYBLUE (-1310 1525);
FORCEPROP 1 LASTPIN (-1350 1650) $PN 1
J 0
(-1345 1612);
DISPLAY 0.617021 (-1345 1612);
PAINT WHITE (-1345 1612);
FORCEPROP 1 LAST TOLERANCE 1%
J 0
(-1305 1575);
DISPLAY 0.617021 (-1305 1575);
PAINT SKYBLUE (-1305 1575);
FORCEPROP 1 LAST VALUE 6.34K
J 0
(-1305 1625);
DISPLAY 0.617021 (-1305 1625);
PAINT SKYBLUE (-1305 1625);
FORCEPROP 1 LAST LOCATION R4B4
J 0
(-1305 1675);
DISPLAY 0.617021 (-1305 1675);
PAINT AQUA (-1305 1675);
FORCEPROP 1 LAST PART_NUMBER G21796-146
J 0
(-1310 1425);
DISPLAY 0.617021 (-1310 1425);
PAINT BLUE (-1310 1425);
FORCEPROP 2 LAST ROOM PVPP_KLM_VR
R 1
J 0
(-1550 1600);
DISPLAY 1.042553 (-1550 1600);
PAINT GREEN (-1550 1600);
DISPLAY INVISIBLE (-1550 1600);
FORCEPROP 2 LAST BOM_COST PVPP_KLM_VR
R 1
J 0
(-1650 1600);
DISPLAY 1.042553 (-1650 1600);
PAINT WHITE (-1650 1600);
DISPLAY INVISIBLE (-1650 1600);
FORCEPROP 2 LAST CDS_LIB mstr_discrete
R 1
J 0
(-1350 1550);
PAINT MONO (-1350 1550);
DISPLAY INVISIBLE (-1350 1550);
FORCEPROP 2 LAST CDS_LOCATION R4B4
J 0
(-1305 1675);
DISPLAY 0.617021 (-1305 1675);
PAINT AQUA (-1305 1675);
DISPLAY INVISIBLE (-1305 1675);
FORCEPROP 1 LAST PATH I216
J 0
(-1300 1725);
DISPLAY 0.978723 (-1300 1725);
PAINT WHITE (-1300 1725);
DISPLAY INVISIBLE (-1300 1725);
FORCEPROP 2 LAST $SEC 1
J 0
(-1300 1775);
DISPLAY 0.680851 (-1300 1775);
PAINT MONO (-1300 1775);
DISPLAY INVISIBLE (-1300 1775);
FORCEPROP 2 LAST CDS_SEC 1
J 0
(-1300 1775);
DISPLAY 1.042553 (-1300 1775);
PAINT ORANGE (-1300 1775);
DISPLAY INVISIBLE (-1300 1775);
FORCEPROP 2 LAST REUSE_ID 7
J 0
(-1300 1775);
DISPLAY 1.042553 (-1300 1775);
PAINT ORANGE (-1300 1775);
DISPLAY INVISIBLE (-1300 1775);
FORCEPROP 0 LAST SPOF TRUE
J 0
(-1300 1775);
DISPLAY 1.021277 (-1300 1775);
PAINT ORANGE (-1300 1775);
DISPLAY INVISIBLE (-1300 1775);
FORCEADD CAP..1
(-1025 2075);
FORCEPROP 1 LASTPIN (-1025 1975) $PN 2
J 0
(-1015 1955);
DISPLAY 0.617021 (-1015 1955);
PAINT ORANGE (-1015 1955);
FORCEPROP 1 LAST MATERIAL X7R
J 0
(-975 1975);
DISPLAY 0.617021 (-975 1975);
PAINT SKYBLUE (-975 1975);
FORCEPROP 1 LAST PACK_TYPE 0402LF
J 0
(-975 1875);
DISPLAY 0.617021 (-975 1875);
PAINT SKYBLUE (-975 1875);
FORCEPROP 1 LAST PART_NUMBER A36096-075
J 0
(-975 1925);
DISPLAY 0.617021 (-975 1925);
PAINT BLUE (-975 1925);
FORCEPROP 1 LAST TOLERANCE 10%
J 0
(-975 2025);
DISPLAY 0.617021 (-975 2025);
PAINT SKYBLUE (-975 2025);
FORCEPROP 1 LASTPIN (-1025 2175) $PN 1
J 0
(-1015 2155);
DISPLAY 0.617021 (-1015 2155);
PAINT ORANGE (-1015 2155);
FORCEPROP 1 LAST VOLTAGE 50V
J 0
(-975 2075);
DISPLAY 0.617021 (-975 2075);
PAINT SKYBLUE (-975 2075);
FORCEPROP 1 LAST VALUE 2200PF
J 0
(-975 2125);
DISPLAY 0.617021 (-975 2125);
PAINT SKYBLUE (-975 2125);
FORCEPROP 1 LAST LOCATION C4B7
J 0
(-975 2175);
DISPLAY 0.617021 (-975 2175);
PAINT AQUA (-975 2175);
FORCEPROP 2 LAST CDS_LIB mstr_discrete
J 0
(-1025 2075);
PAINT ORANGE (-1025 2075);
DISPLAY INVISIBLE (-1025 2075);
FORCEPROP 2 LAST ROOM PVPP_KLM_VR
J 0
(-975 2200);
PAINT GREEN (-975 2200);
DISPLAY INVISIBLE (-975 2200);
FORCEPROP 1 LAST PATH I218
J 0
(-975 2225);
DISPLAY 0.978723 (-975 2225);
PAINT WHITE (-975 2225);
DISPLAY INVISIBLE (-975 2225);
FORCEPROP 2 LAST CDS_LOCATION C4B7
J 0
(-975 2175);
DISPLAY 0.617021 (-975 2175);
PAINT AQUA (-975 2175);
DISPLAY INVISIBLE (-975 2175);
FORCEPROP 2 LAST SEC 1
J 0
(-975 2275);
DISPLAY 0.680851 (-975 2275);
PAINT MONO (-975 2275);
DISPLAY INVISIBLE (-975 2275);
FORCEPROP 2 LAST SEC_TYPE 0402LF
J 0
(-975 2275);
DISPLAY 1.021277 (-975 2275);
PAINT ORANGE (-975 2275);
DISPLAY INVISIBLE (-975 2275);
FORCEPROP 2 LAST REUSE_ID 26
J 0
(-975 2275);
DISPLAY 1.042553 (-975 2275);
PAINT ORANGE (-975 2275);
DISPLAY INVISIBLE (-975 2275);
FORCEPROP 2 LAST BOM_COST PVPP_KLM_VR
J 0
(-975 2225);
DISPLAY 1.042553 (-975 2225);
PAINT WHITE (-975 2225);
DISPLAY INVISIBLE (-975 2225);
FORCEPROP 0 LAST SPOF TRUE
J 0
(-975 2275);
DISPLAY 1.021277 (-975 2275);
PAINT ORANGE (-975 2275);
DISPLAY INVISIBLE (-975 2275);
FORCEADD RES..2
(-1025 2625);
FORCEPROP 1 LAST PART_NUMBER G85996-004
J 0
(-1010 2450);
DISPLAY 0.617021 (-1010 2450);
PAINT BLUE (-1010 2450);
FORCEPROP 1 LAST MATERIAL CHIP
J 0
(-985 2500);
DISPLAY 0.617021 (-985 2500);
PAINT SKYBLUE (-985 2500);
FORCEPROP 1 LASTPIN (-1025 2525) $PN 2
J 0
(-1020 2535);
DISPLAY 0.617021 (-1020 2535);
PAINT ORANGE (-1020 2535);
FORCEPROP 1 LAST PACK_TYPE 0402
J 0
(-985 2550);
DISPLAY 0.617021 (-985 2550);
PAINT SKYBLUE (-985 2550);
FORCEPROP 1 LASTPIN (-1025 2725) $PN 1
J 0
(-1020 2687);
DISPLAY 0.617021 (-1020 2687);
PAINT ORANGE (-1020 2687);
FORCEPROP 1 LAST WATTAGE 1/16W
J 0
(-985 2600);
DISPLAY 0.617021 (-985 2600);
PAINT SKYBLUE (-985 2600);
FORCEPROP 1 LAST TOLERANCE 0.1%
J 0
(-980 2650);
DISPLAY 0.617021 (-980 2650);
PAINT SKYBLUE (-980 2650);
FORCEPROP 1 LAST VALUE 1.0K
J 0
(-980 2700);
DISPLAY 0.617021 (-980 2700);
PAINT SKYBLUE (-980 2700);
FORCEPROP 1 LAST LOCATION R4B9
J 0
(-980 2750);
DISPLAY 0.617021 (-980 2750);
PAINT AQUA (-980 2750);
FORCEPROP 2 LAST CDS_LIB mstr_discrete
J 0
(-1025 2625);
PAINT MONO (-1025 2625);
DISPLAY INVISIBLE (-1025 2625);
FORCEPROP 2 LAST ROOM PVPP_KLM_VR
J 0
(-980 2780);
PAINT GREEN (-980 2780);
DISPLAY INVISIBLE (-980 2780);
FORCEPROP 1 LAST PATH I219
J 0
(-975 2800);
DISPLAY 0.978723 (-975 2800);
PAINT WHITE (-975 2800);
DISPLAY INVISIBLE (-975 2800);
FORCEPROP 2 LAST CDS_LOCATION R4B9
J 0
(-980 2750);
DISPLAY 0.617021 (-980 2750);
PAINT AQUA (-980 2750);
DISPLAY INVISIBLE (-980 2750);
FORCEPROP 2 LAST SEC 1
J 0
(-975 2850);
DISPLAY 0.680851 (-975 2850);
PAINT MONO (-975 2850);
DISPLAY INVISIBLE (-975 2850);
FORCEPROP 2 LAST SEC_TYPE 0402
J 0
(-975 2850);
DISPLAY 1.021277 (-975 2850);
PAINT ORANGE (-975 2850);
DISPLAY INVISIBLE (-975 2850);
FORCEPROP 2 LAST REUSE_ID 9
J 0
(-975 2850);
DISPLAY 1.042553 (-975 2850);
PAINT ORANGE (-975 2850);
DISPLAY INVISIBLE (-975 2850);
FORCEPROP 2 LAST BOM_COST PVPP_KLM_VR
J 0
(-980 2805);
DISPLAY 1.042553 (-980 2805);
PAINT WHITE (-980 2805);
DISPLAY INVISIBLE (-980 2805);
FORCEPROP 0 LAST SPOF TRUE
J 0
(-975 2850);
DISPLAY 1.021277 (-975 2850);
PAINT ORANGE (-975 2850);
DISPLAY INVISIBLE (-975 2850);
FORCEADD RES..1
(-5925 2825);
FORCEPROP 1 LAST WATTAGE 1/16W
J 2
(-5950 2675);
DISPLAY 0.617021 (-5950 2675);
PAINT SKYBLUE (-5950 2675);
FORCEPROP 1 LAST TOLERANCE 5%
J 0
(-5975 2725);
DISPLAY 0.617021 (-5975 2725);
PAINT SKYBLUE (-5975 2725);
FORCEPROP 1 LAST VALUE 0.0
J 2
(-6025 2725);
DISPLAY 0.617021 (-6025 2725);
PAINT SKYBLUE (-6025 2725);
FORCEPROP 1 LAST MATERIAL CHIP
J 0
(-5925 2675);
DISPLAY 0.617021 (-5925 2675);
PAINT SKYBLUE (-5925 2675);
FORCEPROP 1 LAST PART_NUMBER G21497-005
J 0
(-6075 2775);
DISPLAY 0.617021 (-6075 2775);
PAINT BLUE (-6075 2775);
FORCEPROP 1 LAST LOCATION R4B1
J 0
(-5975 2875);
DISPLAY 0.617021 (-5975 2875);
PAINT AQUA (-5975 2875);
FORCEPROP 1 LAST PACK_TYPE 0402
J 0
(-5850 2725);
DISPLAY 0.617021 (-5850 2725);
PAINT SKYBLUE (-5850 2725);
FORCEPROP 2 LAST CDS_LIB mstr_discrete
J 0
(-5925 2825);
PAINT ORANGE (-5925 2825);
DISPLAY INVISIBLE (-5925 2825);
FORCEPROP 2 LAST CDS_SEC 1
J 0
(-5975 3025);
PAINT MONO (-5975 3025);
DISPLAY INVISIBLE (-5975 3025);
FORCEPROP 2 LAST $SEC 1
J 0
(-5975 3025);
PAINT MONO (-5975 3025);
DISPLAY INVISIBLE (-5975 3025);
FORCEPROP 2 LAST CDS_LOCATION R4B1
J 0
(-5975 2875);
DISPLAY 0.617021 (-5975 2875);
PAINT AQUA (-5975 2875);
DISPLAY INVISIBLE (-5975 2875);
FORCEPROP 1 LAST PATH I220
J 0
(-5975 2975);
DISPLAY 0.978723 (-5975 2975);
PAINT WHITE (-5975 2975);
DISPLAY INVISIBLE (-5975 2975);
FORCEPROP 2 LAST ROOM PVCCIN_CPU0_VR
J 0
(-5975 2925);
DISPLAY 1.361702 (-5975 2925);
PAINT ORANGE (-5975 2925);
DISPLAY INVISIBLE (-5975 2925);
FORCEPROP 1 LASTPIN (-6025 2825) $PN 1
J 0
(-6013 2837);
DISPLAY 0.787234 (-6013 2837);
PAINT ORANGE (-6013 2837);
DISPLAY INVISIBLE (-6013 2837);
FORCEPROP 1 LASTPIN (-5825 2825) $PN 2
J 0
(-5863 2837);
DISPLAY 0.787234 (-5863 2837);
PAINT ORANGE (-5863 2837);
DISPLAY INVISIBLE (-5863 2837);
FORCEADD AGND_SCSI..1
(-1350 1175);
FORCEPROP 3 LASTPIN (-1350 1225) SIG_NAME AGND_PVPP_KLM\g
J 0
(-1340 1235);
DISPLAY 0.659574 (-1340 1235);
PAINT MONO (-1340 1235);
DISPLAY INVISIBLE (-1340 1235);
FORCEPROP 1 LAST HDL_POWER AGND_PVPP_KLM
J 1
(-1275 1100);
DISPLAY 0.617021 (-1275 1100);
PAINT GREEN (-1275 1100);
FORCEPROP 1 LAST VOLTAGE 0.0V
J 0
(-1395 1132);
DISPLAY 0.340426 (-1395 1132);
PAINT SKYBLUE (-1395 1132);
DISPLAY INVISIBLE (-1395 1132);
FORCEPROP 2 LAST ROOM PVPP_KLM_VR
J 0
(-1500 1125);
DISPLAY 1.042553 (-1500 1125);
PAINT GREEN (-1500 1125);
DISPLAY INVISIBLE (-1500 1125);
FORCEPROP 1 LAST BODY_TYPE PLUMBING
J 0
(-1395 1132);
DISPLAY 0.340426 (-1395 1132);
PAINT GREEN (-1395 1132);
DISPLAY INVISIBLE (-1395 1132);
FORCEPROP 2 LAST CDS_LIB mstr_symbols
J 0
(-1350 1175);
PAINT ORANGE (-1350 1175);
DISPLAY INVISIBLE (-1350 1175);
FORCEPROP 2 LAST BOM_COST PVPP_KLM_VR
J 0
(-1500 1125);
DISPLAY 1.042553 (-1500 1125);
PAINT WHITE (-1500 1125);
DISPLAY INVISIBLE (-1500 1125);
FORCEPROP 1 LAST PATH I221
J 0
(-1275 1175);
DISPLAY 0.872340 (-1275 1175);
PAINT AQUA (-1275 1175);
DISPLAY INVISIBLE (-1275 1175);
FORCEADD GND..1
(-1450 550);
FORCEPROP 3 LASTPIN (-1450 600) SIG_NAME GND\g
J 0
(-1440 610);
DISPLAY 0.659574 (-1440 610);
PAINT MONO (-1440 610);
DISPLAY INVISIBLE (-1440 610);
FORCEPROP 2 LAST BOM_COST PVPP_KLM_VR
J 0
(-2300 625);
DISPLAY 1.042553 (-2300 625);
PAINT WHITE (-2300 625);
DISPLAY INVISIBLE (-2300 625);
FORCEPROP 2 LAST ROOM PVPP_KLM_VR
J 0
(-2025 625);
DISPLAY 1.042553 (-2025 625);
PAINT GREEN (-2025 625);
DISPLAY INVISIBLE (-2025 625);
FORCEPROP 1 LAST BODY_TYPE PLUMBING
J 0
(-1495 507);
DISPLAY 0.340426 (-1495 507);
PAINT GREEN (-1495 507);
DISPLAY INVISIBLE (-1495 507);
FORCEPROP 1 LAST SIZE 1B
J 0
(-1375 500);
DISPLAY 0.872340 (-1375 500);
PAINT AQUA (-1375 500);
DISPLAY INVISIBLE (-1375 500);
FORCEPROP 1 LAST HDL_POWER GND
J 0
(-1450 700);
DISPLAY 0.872340 (-1450 700);
PAINT GREEN (-1450 700);
DISPLAY INVISIBLE (-1450 700);
FORCEPROP 1 LAST PATH I27
J 0
(-1375 550);
DISPLAY 0.872340 (-1375 550);
PAINT AQUA (-1375 550);
DISPLAY INVISIBLE (-1375 550);
FORCEPROP 2 LAST CDS_LIB mstr_symbols
J 0
(-1450 550);
PAINT MONO (-1450 550);
DISPLAY INVISIBLE (-1450 550);
FORCEPROP 1 LAST VOLTAGE 0
J 0
(-1450 550);
PAINT SKYBLUE (-1450 550);
DISPLAY INVISIBLE (-1450 550);
FORCEADD AGND_SCSI..1
(-900 550);
FORCEPROP 3 LASTPIN (-900 600) SIG_NAME AGND_PVPP_KLM\g
J 0
(-890 610);
DISPLAY 0.659574 (-890 610);
PAINT MONO (-890 610);
DISPLAY INVISIBLE (-890 610);
FORCEPROP 1 LAST HDL_POWER AGND_PVPP_KLM
J 1
(-825 475);
DISPLAY 0.617021 (-825 475);
PAINT GREEN (-825 475);
FORCEPROP 2 LAST ROOM PVPP_KLM_VR
J 0
(-1050 500);
DISPLAY 1.042553 (-1050 500);
PAINT GREEN (-1050 500);
DISPLAY INVISIBLE (-1050 500);
FORCEPROP 2 LAST BOM_COST PVPP_KLM_VR
J 0
(-1050 500);
DISPLAY 1.042553 (-1050 500);
PAINT WHITE (-1050 500);
DISPLAY INVISIBLE (-1050 500);
FORCEPROP 1 LAST VOLTAGE 0.0V
J 0
(-945 507);
DISPLAY 0.340426 (-945 507);
PAINT SKYBLUE (-945 507);
DISPLAY INVISIBLE (-945 507);
FORCEPROP 1 LAST BODY_TYPE PLUMBING
J 0
(-945 507);
DISPLAY 0.340426 (-945 507);
PAINT GREEN (-945 507);
DISPLAY INVISIBLE (-945 507);
FORCEPROP 2 LAST CDS_LIB mstr_symbols
J 0
(-900 550);
PAINT ORANGE (-900 550);
DISPLAY INVISIBLE (-900 550);
FORCEPROP 1 LAST PATH I28
J 0
(-825 550);
DISPLAY 0.872340 (-825 550);
PAINT AQUA (-825 550);
DISPLAY INVISIBLE (-825 550);
FORCEADD RES..1
(-1150 650);
FORCEPROP 1 LAST PACK_TYPE 0402
J 0
(-1225 450);
DISPLAY 0.617021 (-1225 450);
PAINT SKYBLUE (-1225 450);
FORCEPROP 1 LAST WATTAGE 1/16W
J 2
(-1150 500);
DISPLAY 0.617021 (-1150 500);
PAINT SKYBLUE (-1150 500);
FORCEPROP 1 LAST MATERIAL CHIP
J 0
(-1150 500);
DISPLAY 0.617021 (-1150 500);
PAINT SKYBLUE (-1150 500);
FORCEPROP 1 LASTPIN (-1250 650) $PN 1
J 0
(-1238 662);
DISPLAY 0.617021 (-1238 662);
PAINT WHITE (-1238 662);
FORCEPROP 1 LAST VALUE 0.0
J 2
(-1175 550);
DISPLAY 0.617021 (-1175 550);
PAINT SKYBLUE (-1175 550);
FORCEPROP 1 LAST LOCATION R4B14
J 0
(-1200 700);
DISPLAY 0.617021 (-1200 700);
PAINT AQUA (-1200 700);
FORCEPROP 1 LAST TOLERANCE 5%
J 0
(-1150 550);
DISPLAY 0.617021 (-1150 550);
PAINT SKYBLUE (-1150 550);
FORCEPROP 1 LASTPIN (-1050 650) $PN 2
J 0
(-1088 662);
DISPLAY 0.617021 (-1088 662);
PAINT WHITE (-1088 662);
FORCEPROP 1 LAST PART_NUMBER G21497-005
J 0
(-1275 600);
DISPLAY 0.617021 (-1275 600);
PAINT BLUE (-1275 600);
FORCEPROP 2 LAST ROOM PVPP_KLM_VR
J 0
(-1200 725);
PAINT GREEN (-1200 725);
DISPLAY INVISIBLE (-1200 725);
FORCEPROP 2 LAST CDS_LIB mstr_discrete
J 0
(-1150 650);
PAINT MONO (-1150 650);
DISPLAY INVISIBLE (-1150 650);
FORCEPROP 2 LAST CDS_SEC 1
J 0
(-1190 835);
PAINT MONO (-1190 835);
DISPLAY INVISIBLE (-1190 835);
FORCEPROP 2 LAST $SEC 1
J 0
(-1185 855);
PAINT MONO (-1185 855);
DISPLAY INVISIBLE (-1185 855);
FORCEPROP 1 LAST PATH I29
J 0
(-1200 800);
DISPLAY 0.978723 (-1200 800);
PAINT WHITE (-1200 800);
DISPLAY INVISIBLE (-1200 800);
FORCEADD GND..1
(-825 3475);
FORCEPROP 2 LAST BOM_COST PVPP_KLM_VR
J 0
(-1675 3550);
DISPLAY 1.042553 (-1675 3550);
PAINT WHITE (-1675 3550);
DISPLAY INVISIBLE (-1675 3550);
FORCEPROP 2 LAST ROOM PVPP_KLM_VR
J 0
(-1400 3550);
DISPLAY 1.042553 (-1400 3550);
PAINT GREEN (-1400 3550);
DISPLAY INVISIBLE (-1400 3550);
FORCEPROP 1 LAST BODY_TYPE PLUMBING
J 0
(-870 3432);
DISPLAY 0.340426 (-870 3432);
PAINT GREEN (-870 3432);
DISPLAY INVISIBLE (-870 3432);
FORCEPROP 1 LAST VOLTAGE 0
J 0
(-825 3475);
PAINT SKYBLUE (-825 3475);
DISPLAY INVISIBLE (-825 3475);
FORCEPROP 2 LAST CDS_LIB mstr_symbols
J 0
(-825 3475);
PAINT MONO (-825 3475);
DISPLAY INVISIBLE (-825 3475);
FORCEPROP 1 LAST SIZE 1B
J 0
(-750 3425);
DISPLAY 0.872340 (-750 3425);
PAINT GREEN (-750 3425);
DISPLAY INVISIBLE (-750 3425);
FORCEPROP 1 LAST PATH I66
J 0
(-750 3475);
DISPLAY 0.872340 (-750 3475);
PAINT AQUA (-750 3475);
DISPLAY INVISIBLE (-750 3475);
FORCEPROP 1 LAST HDL_POWER GND
J 0
(-825 3625);
DISPLAY 0.872340 (-825 3625);
PAINT GREEN (-825 3625);
DISPLAY INVISIBLE (-825 3625);
FORCEADD CAP..1
(-5150 725);
FORCEPROP 1 LASTPIN (-5150 825) $PN 1
J 0
(-5140 805);
DISPLAY 0.617021 (-5140 805);
PAINT GREEN (-5140 805);
FORCEPROP 1 LASTPIN (-5150 625) $PN 2
J 0
(-5140 605);
DISPLAY 0.617021 (-5140 605);
PAINT GREEN (-5140 605);
FORCEPROP 1 LAST MATERIAL X6S
J 0
(-5100 625);
DISPLAY 0.617021 (-5100 625);
PAINT SKYBLUE (-5100 625);
FORCEPROP 1 LAST PACK_TYPE 0603LF
J 0
(-5100 525);
DISPLAY 0.617021 (-5100 525);
PAINT SKYBLUE (-5100 525);
FORCEPROP 1 LAST TOLERANCE 20%
J 0
(-5100 675);
DISPLAY 0.617021 (-5100 675);
PAINT SKYBLUE (-5100 675);
FORCEPROP 1 LAST VALUE 10UF
J 0
(-5100 775);
DISPLAY 0.617021 (-5100 775);
PAINT SKYBLUE (-5100 775);
FORCEPROP 1 LAST PART_NUMBER E15431-001
J 0
(-5100 575);
DISPLAY 0.617021 (-5100 575);
PAINT BLUE (-5100 575);
FORCEPROP 1 LAST LOCATION C3B2
J 0
(-5100 825);
DISPLAY 0.617021 (-5100 825);
PAINT AQUA (-5100 825);
FORCEPROP 2 LAST CDS_LIB mstr_discrete
J 0
(-5150 725);
PAINT MONO (-5150 725);
DISPLAY INVISIBLE (-5150 725);
FORCEPROP 2 LAST ROOM PVPP_KLM_VR
J 0
(-5100 875);
PAINT MONO (-5100 875);
DISPLAY INVISIBLE (-5100 875);
FORCEPROP 1 LAST PATH I84
J 0
(-5100 875);
DISPLAY 0.978723 (-5100 875);
PAINT WHITE (-5100 875);
DISPLAY INVISIBLE (-5100 875);
FORCEPROP 2 LAST CDS_LOCATION C3B2
J 0
(-5100 825);
DISPLAY 0.617021 (-5100 825);
PAINT AQUA (-5100 825);
DISPLAY INVISIBLE (-5100 825);
FORCEPROP 2 LAST SEC 1
J 0
(-5080 945);
DISPLAY 0.680851 (-5080 945);
PAINT MONO (-5080 945);
DISPLAY INVISIBLE (-5080 945);
FORCEPROP 2 LAST SEC_TYPE 0603LF
J 0
(-5080 945);
DISPLAY 1.021277 (-5080 945);
PAINT ORANGE (-5080 945);
DISPLAY INVISIBLE (-5080 945);
FORCEPROP 2 LAST BOM_COST MEM_VRD_PVPP_AB
J 0
(-5100 875);
PAINT MONO (-5100 875);
DISPLAY INVISIBLE (-5100 875);
FORCEPROP 1 LAST VOLTAGE 4V
J 0
(-5100 725);
PAINT SKYBLUE (-5100 725);
DISPLAY INVISIBLE (-5100 725);
FORCEADD GND..1
(-5225 400);
FORCEPROP 3 LASTPIN (-5225 450) SIG_NAME GND\g
J 0
(-5215 460);
DISPLAY 0.659574 (-5215 460);
PAINT MONO (-5215 460);
DISPLAY INVISIBLE (-5215 460);
FORCEPROP 2 LAST ROOM PVPP_KLM_VR
J 0
(-5775 475);
PAINT ORANGE (-5775 475);
DISPLAY INVISIBLE (-5775 475);
FORCEPROP 1 LAST BODY_TYPE PLUMBING
J 0
(-5270 357);
DISPLAY 0.340426 (-5270 357);
PAINT GREEN (-5270 357);
DISPLAY INVISIBLE (-5270 357);
FORCEPROP 1 LAST SIZE 1B
J 0
(-5150 350);
DISPLAY 0.893617 (-5150 350);
PAINT GREEN (-5150 350);
DISPLAY INVISIBLE (-5150 350);
FORCEPROP 2 LAST CDS_LIB mstr_symbols
J 0
(-5225 400);
PAINT MONO (-5225 400);
DISPLAY INVISIBLE (-5225 400);
FORCEPROP 1 LAST VOLTAGE 0
J 0
(-5225 400);
PAINT SKYBLUE (-5225 400);
DISPLAY INVISIBLE (-5225 400);
FORCEPROP 1 LAST PATH I85
J 0
(-5150 400);
DISPLAY 0.872340 (-5150 400);
PAINT AQUA (-5150 400);
DISPLAY INVISIBLE (-5150 400);
FORCEPROP 2 LAST BOM_COST MEM_VRD_PVPP_AB
J 0
(-5550 475);
PAINT MONO (-5550 475);
DISPLAY INVISIBLE (-5550 475);
FORCEPROP 1 LAST HDL_POWER GND
J 0
(-5225 550);
DISPLAY 0.893617 (-5225 550);
PAINT GREEN (-5225 550);
DISPLAY INVISIBLE (-5225 550);
FORCEADD CAP..1
(-5400 700);
FORCEPROP 1 LAST PACK_TYPE 0603LF
J 0
(-5350 500);
DISPLAY 0.617021 (-5350 500);
PAINT SKYBLUE (-5350 500);
FORCEPROP 1 LASTPIN (-5400 800) $PN 1
J 0
(-5390 780);
DISPLAY 0.617021 (-5390 780);
PAINT GREEN (-5390 780);
FORCEPROP 1 LASTPIN (-5400 600) $PN 2
J 0
(-5390 580);
DISPLAY 0.617021 (-5390 580);
PAINT GREEN (-5390 580);
FORCEPROP 1 LAST TOLERANCE 20%
J 0
(-5350 650);
DISPLAY 0.617021 (-5350 650);
PAINT SKYBLUE (-5350 650);
FORCEPROP 1 LAST MATERIAL X6S
J 0
(-5350 600);
DISPLAY 0.617021 (-5350 600);
PAINT SKYBLUE (-5350 600);
FORCEPROP 1 LAST VALUE 10UF
J 0
(-5350 750);
DISPLAY 0.617021 (-5350 750);
PAINT SKYBLUE (-5350 750);
FORCEPROP 1 LAST LOCATION C3A8
J 0
(-5350 800);
DISPLAY 0.617021 (-5350 800);
PAINT AQUA (-5350 800);
FORCEPROP 1 LAST PART_NUMBER E15431-001
J 0
(-5350 550);
DISPLAY 0.617021 (-5350 550);
PAINT BLUE (-5350 550);
FORCEPROP 2 LAST CDS_LIB mstr_discrete
J 0
(-5400 700);
PAINT MONO (-5400 700);
DISPLAY INVISIBLE (-5400 700);
FORCEPROP 1 LAST VOLTAGE 4V
J 0
(-5350 700);
PAINT SKYBLUE (-5350 700);
DISPLAY INVISIBLE (-5350 700);
FORCEPROP 2 LAST BOM_COST MEM_VRD_PVPP_AB
J 0
(-5350 850);
PAINT MONO (-5350 850);
DISPLAY INVISIBLE (-5350 850);
FORCEPROP 2 LAST CDS_SEC 1
J 0
(-5350 900);
PAINT MONO (-5350 900);
DISPLAY INVISIBLE (-5350 900);
FORCEPROP 2 LAST $SEC 1
J 0
(-5350 900);
PAINT MONO (-5350 900);
DISPLAY INVISIBLE (-5350 900);
FORCEPROP 2 LAST CDS_LOCATION C3A8
J 0
(-5350 800);
DISPLAY 0.617021 (-5350 800);
PAINT AQUA (-5350 800);
DISPLAY INVISIBLE (-5350 800);
FORCEPROP 1 LAST PATH I86
J 0
(-5350 850);
DISPLAY 0.978723 (-5350 850);
PAINT WHITE (-5350 850);
DISPLAY INVISIBLE (-5350 850);
FORCEPROP 2 LAST ROOM PVPP_KLM_VR
J 0
(-5350 850);
PAINT MONO (-5350 850);
DISPLAY INVISIBLE (-5350 850);
FORCEADD CAP..1
(-5675 700);
FORCEPROP 1 LASTPIN (-5675 600) $PN 2
J 0
(-5665 580);
DISPLAY 0.617021 (-5665 580);
PAINT GREEN (-5665 580);
FORCEPROP 1 LASTPIN (-5675 800) $PN 1
J 0
(-5665 780);
DISPLAY 0.617021 (-5665 780);
PAINT GREEN (-5665 780);
FORCEPROP 1 LAST PACK_TYPE 0603LF
J 0
(-5625 500);
DISPLAY 0.617021 (-5625 500);
PAINT SKYBLUE (-5625 500);
FORCEPROP 1 LAST MATERIAL X6S
J 0
(-5625 600);
DISPLAY 0.617021 (-5625 600);
PAINT SKYBLUE (-5625 600);
FORCEPROP 1 LAST TOLERANCE 20%
J 0
(-5625 650);
DISPLAY 0.617021 (-5625 650);
PAINT SKYBLUE (-5625 650);
FORCEPROP 1 LAST VALUE 10UF
J 0
(-5625 750);
DISPLAY 0.617021 (-5625 750);
PAINT SKYBLUE (-5625 750);
FORCEPROP 1 LAST LOCATION C7L3
J 0
(-5625 800);
DISPLAY 0.617021 (-5625 800);
PAINT AQUA (-5625 800);
FORCEPROP 1 LAST PART_NUMBER E15431-001
J 0
(-5625 550);
DISPLAY 0.617021 (-5625 550);
PAINT BLUE (-5625 550);
FORCEPROP 2 LAST CDS_LIB mstr_discrete
J 0
(-5675 700);
PAINT MONO (-5675 700);
DISPLAY INVISIBLE (-5675 700);
FORCEPROP 1 LAST VOLTAGE 4V
J 0
(-5625 700);
PAINT SKYBLUE (-5625 700);
DISPLAY INVISIBLE (-5625 700);
FORCEPROP 2 LAST ROOM PVPP_KLM_VR
J 0
(-5625 850);
PAINT MONO (-5625 850);
DISPLAY INVISIBLE (-5625 850);
FORCEPROP 1 LAST PATH I87
J 0
(-5625 850);
DISPLAY 0.978723 (-5625 850);
PAINT WHITE (-5625 850);
DISPLAY INVISIBLE (-5625 850);
FORCEPROP 2 LAST CDS_LOCATION C7L3
J 0
(-5625 800);
DISPLAY 0.617021 (-5625 800);
PAINT AQUA (-5625 800);
DISPLAY INVISIBLE (-5625 800);
FORCEPROP 2 LAST $SEC 1
J 0
(-5625 900);
PAINT MONO (-5625 900);
DISPLAY INVISIBLE (-5625 900);
FORCEPROP 2 LAST BOM_COST MEM_VRD_PVPP_AB
J 0
(-5625 850);
PAINT MONO (-5625 850);
DISPLAY INVISIBLE (-5625 850);
FORCEPROP 2 LAST CDS_SEC 1
J 0
(-5625 900);
PAINT MONO (-5625 900);
DISPLAY INVISIBLE (-5625 900);
FORCEADD CAP..1
(-5950 725);
FORCEPROP 1 LASTPIN (-5950 625) $PN 2
J 0
(-5940 605);
DISPLAY 0.617021 (-5940 605);
PAINT GREEN (-5940 605);
FORCEPROP 1 LASTPIN (-5950 825) $PN 1
J 0
(-5940 805);
DISPLAY 0.617021 (-5940 805);
PAINT GREEN (-5940 805);
FORCEPROP 1 LAST MATERIAL X6S
J 0
(-5900 625);
DISPLAY 0.617021 (-5900 625);
PAINT SKYBLUE (-5900 625);
FORCEPROP 1 LAST PACK_TYPE 0603LF
J 0
(-5900 525);
DISPLAY 0.617021 (-5900 525);
PAINT SKYBLUE (-5900 525);
FORCEPROP 1 LAST TOLERANCE 20%
J 0
(-5900 675);
DISPLAY 0.617021 (-5900 675);
PAINT SKYBLUE (-5900 675);
FORCEPROP 1 LAST VALUE 10UF
J 0
(-5900 775);
DISPLAY 0.617021 (-5900 775);
PAINT SKYBLUE (-5900 775);
FORCEPROP 1 LAST LOCATION C7L2
J 0
(-5900 825);
DISPLAY 0.617021 (-5900 825);
PAINT AQUA (-5900 825);
FORCEPROP 1 LAST PART_NUMBER E15431-001
J 0
(-5900 575);
DISPLAY 0.617021 (-5900 575);
PAINT BLUE (-5900 575);
FORCEPROP 1 LAST VOLTAGE 4V
J 0
(-5900 725);
PAINT SKYBLUE (-5900 725);
DISPLAY INVISIBLE (-5900 725);
FORCEPROP 2 LAST CDS_LIB mstr_discrete
J 0
(-5950 725);
PAINT MONO (-5950 725);
DISPLAY INVISIBLE (-5950 725);
FORCEPROP 2 LAST CDS_LOCATION C7L2
J 0
(-5900 825);
DISPLAY 0.617021 (-5900 825);
PAINT AQUA (-5900 825);
DISPLAY INVISIBLE (-5900 825);
FORCEPROP 2 LAST ROOM PVPP_KLM_VR
J 0
(-5900 875);
PAINT MONO (-5900 875);
DISPLAY INVISIBLE (-5900 875);
FORCEPROP 2 LAST BOM_COST MEM_VRD_PVPP_AB
J 0
(-5900 875);
PAINT MONO (-5900 875);
DISPLAY INVISIBLE (-5900 875);
FORCEPROP 1 LAST PATH I88
J 0
(-5900 875);
DISPLAY 0.978723 (-5900 875);
PAINT WHITE (-5900 875);
DISPLAY INVISIBLE (-5900 875);
FORCEPROP 2 LAST $SEC 1
J 0
(-5900 925);
PAINT MONO (-5900 925);
DISPLAY INVISIBLE (-5900 925);
FORCEPROP 2 LAST CDS_SEC 1
J 0
(-5900 925);
PAINT MONO (-5900 925);
DISPLAY INVISIBLE (-5900 925);
FORCEADD CAP..1
(-6250 725);
FORCEPROP 1 LASTPIN (-6250 625) $PN 2
J 0
(-6240 605);
DISPLAY 0.617021 (-6240 605);
PAINT GREEN (-6240 605);
FORCEPROP 1 LASTPIN (-6250 825) $PN 1
J 0
(-6240 805);
DISPLAY 0.617021 (-6240 805);
PAINT GREEN (-6240 805);
FORCEPROP 1 LAST MATERIAL X6S
J 0
(-6200 625);
DISPLAY 0.617021 (-6200 625);
PAINT SKYBLUE (-6200 625);
FORCEPROP 1 LAST PACK_TYPE 0603LF
J 0
(-6200 525);
DISPLAY 0.617021 (-6200 525);
PAINT SKYBLUE (-6200 525);
FORCEPROP 1 LAST TOLERANCE 20%
J 0
(-6200 675);
DISPLAY 0.617021 (-6200 675);
PAINT SKYBLUE (-6200 675);
FORCEPROP 1 LAST VALUE 10UF
J 0
(-6200 775);
DISPLAY 0.617021 (-6200 775);
PAINT SKYBLUE (-6200 775);
FORCEPROP 1 LAST PART_NUMBER E15431-001
J 0
(-6200 575);
DISPLAY 0.617021 (-6200 575);
PAINT BLUE (-6200 575);
FORCEPROP 1 LAST LOCATION C7L7
J 0
(-6200 825);
DISPLAY 0.617021 (-6200 825);
PAINT AQUA (-6200 825);
FORCEPROP 1 LAST VOLTAGE 4V
J 0
(-6200 725);
PAINT SKYBLUE (-6200 725);
DISPLAY INVISIBLE (-6200 725);
FORCEPROP 2 LAST CDS_LIB mstr_discrete
J 0
(-6250 725);
PAINT MONO (-6250 725);
DISPLAY INVISIBLE (-6250 725);
FORCEPROP 2 LAST CDS_LOCATION C7L7
J 0
(-6200 825);
DISPLAY 0.617021 (-6200 825);
PAINT AQUA (-6200 825);
DISPLAY INVISIBLE (-6200 825);
FORCEPROP 2 LAST ROOM PVPP_KLM_VR
J 0
(-6200 875);
PAINT MONO (-6200 875);
DISPLAY INVISIBLE (-6200 875);
FORCEPROP 2 LAST BOM_COST MEM_VRD_PVPP_AB
J 0
(-6200 875);
PAINT MONO (-6200 875);
DISPLAY INVISIBLE (-6200 875);
FORCEPROP 1 LAST PATH I89
J 0
(-6200 875);
DISPLAY 0.978723 (-6200 875);
PAINT WHITE (-6200 875);
DISPLAY INVISIBLE (-6200 875);
FORCEPROP 2 LAST $SEC 1
J 0
(-6200 925);
PAINT MONO (-6200 925);
DISPLAY INVISIBLE (-6200 925);
FORCEPROP 2 LAST CDS_SEC 1
J 0
(-6200 925);
PAINT MONO (-6200 925);
DISPLAY INVISIBLE (-6200 925);
FORCEADD CAP..1
(-6550 725);
FORCEPROP 1 LASTPIN (-6550 625) $PN 2
J 0
(-6540 605);
DISPLAY 0.617021 (-6540 605);
PAINT GREEN (-6540 605);
FORCEPROP 1 LAST MATERIAL X6S
J 0
(-6500 625);
DISPLAY 0.617021 (-6500 625);
PAINT SKYBLUE (-6500 625);
FORCEPROP 1 LAST TOLERANCE 20%
J 0
(-6500 675);
DISPLAY 0.617021 (-6500 675);
PAINT SKYBLUE (-6500 675);
FORCEPROP 1 LASTPIN (-6550 825) $PN 1
J 0
(-6540 805);
DISPLAY 0.617021 (-6540 805);
PAINT GREEN (-6540 805);
FORCEPROP 1 LAST PACK_TYPE 0603LF
J 0
(-6500 525);
DISPLAY 0.617021 (-6500 525);
PAINT SKYBLUE (-6500 525);
FORCEPROP 1 LAST VALUE 10UF
J 0
(-6500 775);
DISPLAY 0.617021 (-6500 775);
PAINT SKYBLUE (-6500 775);
FORCEPROP 1 LAST PART_NUMBER E15431-001
J 0
(-6500 575);
DISPLAY 0.617021 (-6500 575);
PAINT BLUE (-6500 575);
FORCEPROP 1 LAST LOCATION C7L6
J 0
(-6500 825);
DISPLAY 0.617021 (-6500 825);
PAINT AQUA (-6500 825);
FORCEPROP 1 LAST VOLTAGE 4V
J 0
(-6500 725);
PAINT SKYBLUE (-6500 725);
DISPLAY INVISIBLE (-6500 725);
FORCEPROP 2 LAST CDS_LIB mstr_discrete
J 0
(-6550 725);
PAINT MONO (-6550 725);
DISPLAY INVISIBLE (-6550 725);
FORCEPROP 2 LAST ROOM PVPP_KLM_VR
J 0
(-6500 875);
PAINT MONO (-6500 875);
DISPLAY INVISIBLE (-6500 875);
FORCEPROP 1 LAST PATH I90
J 0
(-6500 875);
DISPLAY 0.978723 (-6500 875);
PAINT WHITE (-6500 875);
DISPLAY INVISIBLE (-6500 875);
FORCEPROP 2 LAST CDS_LOCATION C7L6
J 0
(-6500 825);
DISPLAY 0.617021 (-6500 825);
PAINT AQUA (-6500 825);
DISPLAY INVISIBLE (-6500 825);
FORCEPROP 2 LAST $SEC 1
J 0
(-6500 925);
PAINT MONO (-6500 925);
DISPLAY INVISIBLE (-6500 925);
FORCEPROP 2 LAST CDS_SEC 1
J 0
(-6500 925);
PAINT MONO (-6500 925);
DISPLAY INVISIBLE (-6500 925);
FORCEPROP 2 LAST BOM_COST MEM_VRD_PVPP_AB
J 0
(-6500 875);
PAINT MONO (-6500 875);
DISPLAY INVISIBLE (-6500 875);
FORCEADD CAP..1
(-6825 725);
FORCEPROP 1 LASTPIN (-6825 625) $PN 2
J 0
(-6815 605);
DISPLAY 0.617021 (-6815 605);
PAINT GREEN (-6815 605);
FORCEPROP 1 LAST MATERIAL X6S
J 0
(-6775 625);
DISPLAY 0.617021 (-6775 625);
PAINT SKYBLUE (-6775 625);
FORCEPROP 1 LAST TOLERANCE 20%
J 0
(-6775 675);
DISPLAY 0.617021 (-6775 675);
PAINT SKYBLUE (-6775 675);
FORCEPROP 1 LASTPIN (-6825 825) $PN 1
J 0
(-6815 805);
DISPLAY 0.617021 (-6815 805);
PAINT GREEN (-6815 805);
FORCEPROP 1 LAST LOCATION C7M4
J 0
(-6775 825);
DISPLAY 0.617021 (-6775 825);
PAINT AQUA (-6775 825);
FORCEPROP 1 LAST VALUE 10UF
J 0
(-6775 775);
DISPLAY 0.617021 (-6775 775);
PAINT SKYBLUE (-6775 775);
FORCEPROP 1 LAST PACK_TYPE 0603LF
J 0
(-6775 525);
DISPLAY 0.617021 (-6775 525);
PAINT SKYBLUE (-6775 525);
FORCEPROP 1 LAST PART_NUMBER E15431-001
J 0
(-6775 575);
DISPLAY 0.617021 (-6775 575);
PAINT BLUE (-6775 575);
FORCEPROP 1 LAST VOLTAGE 4V
J 0
(-6775 725);
PAINT SKYBLUE (-6775 725);
DISPLAY INVISIBLE (-6775 725);
FORCEPROP 2 LAST CDS_LIB mstr_discrete
J 0
(-6825 725);
PAINT ORANGE (-6825 725);
DISPLAY INVISIBLE (-6825 725);
FORCEPROP 2 LAST ROOM PVPP_KLM_VR
J 0
(-6775 875);
PAINT MONO (-6775 875);
DISPLAY INVISIBLE (-6775 875);
FORCEPROP 1 LAST PATH I91
J 0
(-6775 875);
DISPLAY 0.978723 (-6775 875);
PAINT WHITE (-6775 875);
DISPLAY INVISIBLE (-6775 875);
FORCEPROP 2 LAST CDS_LOCATION C7M4
J 0
(-6775 825);
DISPLAY 0.617021 (-6775 825);
PAINT AQUA (-6775 825);
DISPLAY INVISIBLE (-6775 825);
FORCEPROP 2 LAST $SEC 1
J 0
(-6775 925);
PAINT MONO (-6775 925);
DISPLAY INVISIBLE (-6775 925);
FORCEPROP 2 LAST CDS_SEC 1
J 0
(-6775 925);
PAINT MONO (-6775 925);
DISPLAY INVISIBLE (-6775 925);
FORCEPROP 2 LAST BOM_COST MEM_VRD_PVPP_AB
J 0
(-6775 875);
PAINT MONO (-6775 875);
DISPLAY INVISIBLE (-6775 875);
FORCEADD CAP..1
(-7125 725);
FORCEPROP 1 LASTPIN (-7125 625) $PN 2
J 0
(-7115 605);
DISPLAY 0.617021 (-7115 605);
PAINT GREEN (-7115 605);
FORCEPROP 1 LAST MATERIAL X6S
J 0
(-7075 625);
DISPLAY 0.617021 (-7075 625);
PAINT SKYBLUE (-7075 625);
FORCEPROP 1 LAST TOLERANCE 20%
J 0
(-7075 675);
DISPLAY 0.617021 (-7075 675);
PAINT SKYBLUE (-7075 675);
FORCEPROP 1 LASTPIN (-7125 825) $PN 1
J 0
(-7115 805);
DISPLAY 0.617021 (-7115 805);
PAINT GREEN (-7115 805);
FORCEPROP 1 LAST LOCATION C7M3
J 0
(-7075 825);
DISPLAY 0.617021 (-7075 825);
PAINT AQUA (-7075 825);
FORCEPROP 1 LAST VALUE 10UF
J 0
(-7075 775);
DISPLAY 0.617021 (-7075 775);
PAINT SKYBLUE (-7075 775);
FORCEPROP 1 LAST PACK_TYPE 0603LF
J 0
(-7075 525);
DISPLAY 0.617021 (-7075 525);
PAINT SKYBLUE (-7075 525);
FORCEPROP 1 LAST PART_NUMBER E15431-001
J 0
(-7075 575);
DISPLAY 0.617021 (-7075 575);
PAINT BLUE (-7075 575);
FORCEPROP 1 LAST VOLTAGE 4V
J 0
(-7075 725);
PAINT SKYBLUE (-7075 725);
DISPLAY INVISIBLE (-7075 725);
FORCEPROP 2 LAST CDS_LIB mstr_discrete
J 0
(-7125 725);
PAINT ORANGE (-7125 725);
DISPLAY INVISIBLE (-7125 725);
FORCEPROP 2 LAST CDS_LOCATION C7M3
J 0
(-7075 825);
DISPLAY 0.617021 (-7075 825);
PAINT AQUA (-7075 825);
DISPLAY INVISIBLE (-7075 825);
FORCEPROP 2 LAST BOM_COST MEM_VRD_PVPP_AB
J 0
(-7075 875);
PAINT MONO (-7075 875);
DISPLAY INVISIBLE (-7075 875);
FORCEPROP 1 LAST PATH I92
J 0
(-7075 875);
DISPLAY 0.978723 (-7075 875);
PAINT WHITE (-7075 875);
DISPLAY INVISIBLE (-7075 875);
FORCEPROP 2 LAST ROOM PVPP_KLM_VR
J 0
(-7075 875);
PAINT MONO (-7075 875);
DISPLAY INVISIBLE (-7075 875);
FORCEPROP 2 LAST CDS_SEC 1
J 0
(-7075 925);
PAINT MONO (-7075 925);
DISPLAY INVISIBLE (-7075 925);
FORCEPROP 2 LAST $SEC 1
J 0
(-7075 925);
PAINT MONO (-7075 925);
DISPLAY INVISIBLE (-7075 925);
FORCEADD CAP..1
(-7400 700);
FORCEPROP 1 LAST PACK_TYPE 0603LF
J 0
(-7350 500);
DISPLAY 0.617021 (-7350 500);
PAINT SKYBLUE (-7350 500);
FORCEPROP 1 LASTPIN (-7400 600) $PN 2
J 0
(-7390 580);
DISPLAY 0.617021 (-7390 580);
PAINT GREEN (-7390 580);
FORCEPROP 1 LAST MATERIAL X6S
J 0
(-7350 600);
DISPLAY 0.617021 (-7350 600);
PAINT SKYBLUE (-7350 600);
FORCEPROP 1 LAST TOLERANCE 20%
J 0
(-7350 650);
DISPLAY 0.617021 (-7350 650);
PAINT SKYBLUE (-7350 650);
FORCEPROP 1 LAST VALUE 10UF
J 0
(-7350 750);
DISPLAY 0.617021 (-7350 750);
PAINT SKYBLUE (-7350 750);
FORCEPROP 1 LASTPIN (-7400 800) $PN 1
J 0
(-7390 780);
DISPLAY 0.617021 (-7390 780);
PAINT GREEN (-7390 780);
FORCEPROP 1 LAST LOCATION C3A4
J 0
(-7350 800);
DISPLAY 0.617021 (-7350 800);
PAINT AQUA (-7350 800);
FORCEPROP 1 LAST PART_NUMBER E15431-001
J 0
(-7350 550);
DISPLAY 0.617021 (-7350 550);
PAINT BLUE (-7350 550);
FORCEPROP 1 LAST VOLTAGE 4V
J 0
(-7350 700);
PAINT SKYBLUE (-7350 700);
DISPLAY INVISIBLE (-7350 700);
FORCEPROP 2 LAST CDS_LIB mstr_discrete
J 0
(-7400 700);
PAINT ORANGE (-7400 700);
DISPLAY INVISIBLE (-7400 700);
FORCEPROP 1 LAST PATH I93
J 0
(-7350 850);
DISPLAY 0.978723 (-7350 850);
PAINT WHITE (-7350 850);
DISPLAY INVISIBLE (-7350 850);
FORCEPROP 2 LAST CDS_LOCATION C3A4
J 0
(-7350 800);
DISPLAY 0.617021 (-7350 800);
PAINT AQUA (-7350 800);
DISPLAY INVISIBLE (-7350 800);
FORCEPROP 2 LAST BOM_COST MEM_VRD_PVPP_AB
J 0
(-7350 850);
PAINT MONO (-7350 850);
DISPLAY INVISIBLE (-7350 850);
FORCEPROP 2 LAST ROOM PVPP_KLM_VR
J 0
(-7350 850);
PAINT MONO (-7350 850);
DISPLAY INVISIBLE (-7350 850);
FORCEPROP 2 LAST $SEC 1
J 0
(-7350 900);
PAINT MONO (-7350 900);
DISPLAY INVISIBLE (-7350 900);
FORCEPROP 2 LAST CDS_SEC 1
J 0
(-7350 900);
PAINT MONO (-7350 900);
DISPLAY INVISIBLE (-7350 900);
FORCEADD CAP..1
(-7650 725);
FORCEPROP 1 LASTPIN (-7650 625) $PN 2
J 0
(-7640 605);
DISPLAY 0.617021 (-7640 605);
PAINT GREEN (-7640 605);
FORCEPROP 1 LAST MATERIAL X6S
J 0
(-7600 625);
DISPLAY 0.617021 (-7600 625);
PAINT SKYBLUE (-7600 625);
FORCEPROP 1 LAST TOLERANCE 20%
J 0
(-7600 675);
DISPLAY 0.617021 (-7600 675);
PAINT SKYBLUE (-7600 675);
FORCEPROP 1 LAST PACK_TYPE 0603LF
J 0
(-7600 525);
DISPLAY 0.617021 (-7600 525);
PAINT SKYBLUE (-7600 525);
FORCEPROP 1 LASTPIN (-7650 825) $PN 1
J 0
(-7640 805);
DISPLAY 0.617021 (-7640 805);
PAINT GREEN (-7640 805);
FORCEPROP 1 LAST VALUE 10UF
J 0
(-7600 775);
DISPLAY 0.617021 (-7600 775);
PAINT SKYBLUE (-7600 775);
FORCEPROP 1 LAST LOCATION C3B1
J 0
(-7600 825);
DISPLAY 0.617021 (-7600 825);
PAINT AQUA (-7600 825);
FORCEPROP 1 LAST PART_NUMBER E15431-001
J 0
(-7600 575);
DISPLAY 0.617021 (-7600 575);
PAINT BLUE (-7600 575);
FORCEPROP 1 LAST VOLTAGE 4V
J 0
(-7600 725);
PAINT SKYBLUE (-7600 725);
DISPLAY INVISIBLE (-7600 725);
FORCEPROP 2 LAST CDS_LIB mstr_discrete
J 0
(-7650 725);
PAINT ORANGE (-7650 725);
DISPLAY INVISIBLE (-7650 725);
FORCEPROP 2 LAST CDS_LOCATION C3B1
J 0
(-7600 825);
DISPLAY 0.617021 (-7600 825);
PAINT AQUA (-7600 825);
DISPLAY INVISIBLE (-7600 825);
FORCEPROP 2 LAST BOM_COST MEM_VRD_PVPP_AB
J 0
(-7600 875);
PAINT MONO (-7600 875);
DISPLAY INVISIBLE (-7600 875);
FORCEPROP 1 LAST PATH I94
J 0
(-7600 875);
DISPLAY 0.978723 (-7600 875);
PAINT WHITE (-7600 875);
DISPLAY INVISIBLE (-7600 875);
FORCEPROP 2 LAST ROOM PVPP_KLM_VR
J 0
(-7600 875);
PAINT MONO (-7600 875);
DISPLAY INVISIBLE (-7600 875);
FORCEPROP 2 LAST $SEC 1
J 0
(-7600 925);
PAINT MONO (-7600 925);
DISPLAY INVISIBLE (-7600 925);
FORCEPROP 2 LAST CDS_SEC 1
J 0
(-7600 925);
PAINT MONO (-7600 925);
DISPLAY INVISIBLE (-7600 925);
FORCEADD CAP..1
(-7925 725);
FORCEPROP 1 LASTPIN (-7925 625) $PN 2
J 0
(-7915 605);
DISPLAY 0.617021 (-7915 605);
PAINT GREEN (-7915 605);
FORCEPROP 1 LAST MATERIAL X6S
J 0
(-7875 625);
DISPLAY 0.617021 (-7875 625);
PAINT SKYBLUE (-7875 625);
FORCEPROP 1 LAST PACK_TYPE 0603LF
J 0
(-7875 525);
DISPLAY 0.617021 (-7875 525);
PAINT SKYBLUE (-7875 525);
FORCEPROP 1 LAST TOLERANCE 20%
J 0
(-7875 675);
DISPLAY 0.617021 (-7875 675);
PAINT SKYBLUE (-7875 675);
FORCEPROP 1 LASTPIN (-7925 825) $PN 1
J 0
(-7915 805);
DISPLAY 0.617021 (-7915 805);
PAINT GREEN (-7915 805);
FORCEPROP 1 LAST VALUE 10UF
J 0
(-7875 775);
DISPLAY 0.617021 (-7875 775);
PAINT SKYBLUE (-7875 775);
FORCEPROP 1 LAST LOCATION C3A7
J 0
(-7875 825);
DISPLAY 0.617021 (-7875 825);
PAINT AQUA (-7875 825);
FORCEPROP 1 LAST PART_NUMBER E15431-001
J 0
(-7875 575);
DISPLAY 0.617021 (-7875 575);
PAINT BLUE (-7875 575);
FORCEPROP 1 LAST VOLTAGE 4V
J 0
(-7875 725);
PAINT SKYBLUE (-7875 725);
DISPLAY INVISIBLE (-7875 725);
FORCEPROP 2 LAST CDS_LIB mstr_discrete
J 0
(-7925 725);
PAINT ORANGE (-7925 725);
DISPLAY INVISIBLE (-7925 725);
FORCEPROP 2 LAST ROOM PVPP_KLM_VR
J 0
(-7875 875);
PAINT MONO (-7875 875);
DISPLAY INVISIBLE (-7875 875);
FORCEPROP 1 LAST PATH I95
J 0
(-7875 875);
DISPLAY 0.978723 (-7875 875);
PAINT WHITE (-7875 875);
DISPLAY INVISIBLE (-7875 875);
FORCEPROP 2 LAST CDS_LOCATION C3A7
J 0
(-7875 825);
DISPLAY 0.617021 (-7875 825);
PAINT AQUA (-7875 825);
DISPLAY INVISIBLE (-7875 825);
FORCEPROP 2 LAST $SEC 1
J 0
(-7875 925);
PAINT MONO (-7875 925);
DISPLAY INVISIBLE (-7875 925);
FORCEPROP 2 LAST CDS_SEC 1
J 0
(-7875 925);
PAINT MONO (-7875 925);
DISPLAY INVISIBLE (-7875 925);
FORCEPROP 2 LAST BOM_COST MEM_VRD_PVPP_AB
J 0
(-7875 875);
PAINT MONO (-7875 875);
DISPLAY INVISIBLE (-7875 875);
FORCEADD PVPP_KLM..1
(-8175 1000);
FORCEPROP 3 LASTPIN (-8175 950) SIG_NAME PVPP_KLM\g
J 0
(-8165 960);
DISPLAY 0.659574 (-8165 960);
PAINT MONO (-8165 960);
DISPLAY INVISIBLE (-8165 960);
FORCEPROP 1 LAST BODY_TYPE PLUMBING
J 0
(-8220 957);
DISPLAY 0.340426 (-8220 957);
PAINT GREEN (-8220 957);
DISPLAY INVISIBLE (-8220 957);
FORCEPROP 1 LAST VOLTAGE 2.5V
J 0
(-8220 957);
DISPLAY 0.340426 (-8220 957);
PAINT SKYBLUE (-8220 957);
DISPLAY INVISIBLE (-8220 957);
FORCEPROP 2 LAST CDS_LIB mstr_symbols
J 0
(-8175 1000);
PAINT ORANGE (-8175 1000);
DISPLAY INVISIBLE (-8175 1000);
FORCEPROP 1 LAST HDL_POWER PVPP_KLM
J 1
(-8175 1050);
DISPLAY 0.872340 (-8175 1050);
PAINT GREEN (-8175 1050);
DISPLAY INVISIBLE (-8175 1050);
FORCEPROP 2 LAST ROOM PVPP_KLM_VR
J 0
(-7925 1100);
PAINT ORANGE (-7925 1100);
DISPLAY INVISIBLE (-7925 1100);
FORCEPROP 1 LAST PATH I96
J 0
(-8125 1025);
DISPLAY 0.872340 (-8125 1025);
PAINT AQUA (-8125 1025);
DISPLAY INVISIBLE (-8125 1025);
FORCEPROP 2 LAST BOM_COST MEM_VRD_PVPP_AB
J 0
(-8100 1100);
PAINT MONO (-8100 1100);
DISPLAY INVISIBLE (-8100 1100);
FORCEADD CAP..1
(-8175 725);
FORCEPROP 1 LASTPIN (-8175 625) $PN 2
J 0
(-8165 605);
DISPLAY 0.617021 (-8165 605);
PAINT GREEN (-8165 605);
FORCEPROP 1 LAST MATERIAL X6S
J 0
(-8125 625);
DISPLAY 0.617021 (-8125 625);
PAINT SKYBLUE (-8125 625);
FORCEPROP 1 LAST PACK_TYPE 0603LF
J 0
(-8125 525);
DISPLAY 0.617021 (-8125 525);
PAINT SKYBLUE (-8125 525);
FORCEPROP 1 LAST TOLERANCE 20%
J 0
(-8125 675);
DISPLAY 0.617021 (-8125 675);
PAINT SKYBLUE (-8125 675);
FORCEPROP 1 LASTPIN (-8175 825) $PN 1
J 0
(-8165 805);
DISPLAY 0.617021 (-8165 805);
PAINT GREEN (-8165 805);
FORCEPROP 1 LAST LOCATION C3A3
J 0
(-8125 825);
DISPLAY 0.617021 (-8125 825);
PAINT AQUA (-8125 825);
FORCEPROP 1 LAST VALUE 10UF
J 0
(-8125 775);
DISPLAY 0.617021 (-8125 775);
PAINT SKYBLUE (-8125 775);
FORCEPROP 1 LAST PART_NUMBER E15431-001
J 0
(-8125 575);
DISPLAY 0.617021 (-8125 575);
PAINT BLUE (-8125 575);
FORCEPROP 2 LAST CDS_LIB mstr_discrete
J 0
(-8175 725);
PAINT ORANGE (-8175 725);
DISPLAY INVISIBLE (-8175 725);
FORCEPROP 1 LAST VOLTAGE 4V
J 0
(-8125 725);
PAINT SKYBLUE (-8125 725);
DISPLAY INVISIBLE (-8125 725);
FORCEPROP 2 LAST CDS_LOCATION C3A3
J 0
(-8125 825);
DISPLAY 0.617021 (-8125 825);
PAINT AQUA (-8125 825);
DISPLAY INVISIBLE (-8125 825);
FORCEPROP 2 LAST BOM_COST MEM_VRD_PVPP_AB
J 0
(-8125 875);
PAINT MONO (-8125 875);
DISPLAY INVISIBLE (-8125 875);
FORCEPROP 1 LAST PATH I97
J 0
(-8125 875);
DISPLAY 0.978723 (-8125 875);
PAINT WHITE (-8125 875);
DISPLAY INVISIBLE (-8125 875);
FORCEPROP 2 LAST ROOM PVPP_KLM_VR
J 0
(-8125 875);
PAINT MONO (-8125 875);
DISPLAY INVISIBLE (-8125 875);
FORCEPROP 2 LAST CDS_SEC 1
J 0
(-8125 925);
PAINT MONO (-8125 925);
DISPLAY INVISIBLE (-8125 925);
FORCEPROP 2 LAST $SEC 1
J 0
(-8125 925);
PAINT MONO (-8125 925);
DISPLAY INVISIBLE (-8125 925);
FORCEADD DNS..2
(-2645 3695);
PAINT RED (-2645 3695);
FORCEPROP 1 LAST COMMENT_BODY TRUE
R 1
J 0
(-2570 3470);
DISPLAY 0.872340 (-2570 3470);
PAINT GREEN (-2570 3470);
DISPLAY INVISIBLE (-2570 3470);
FORCEPROP 2 LAST CDS_LIB mstr_misc
J 0
(-2645 3695);
PAINT ORANGE (-2645 3695);
DISPLAY INVISIBLE (-2645 3695);
FORCEADD DNS..2
(-2645 3345);
PAINT RED (-2645 3345);
FORCEPROP 1 LAST COMMENT_BODY TRUE
R 1
J 0
(-2570 3120);
DISPLAY 0.872340 (-2570 3120);
PAINT GREEN (-2570 3120);
DISPLAY INVISIBLE (-2570 3120);
FORCEPROP 2 LAST CDS_LIB mstr_misc
J 0
(-2645 3345);
PAINT ORANGE (-2645 3345);
DISPLAY INVISIBLE (-2645 3345);
FORCEADD DNS..2
(-6295 2395);
PAINT RED (-6295 2395);
FORCEPROP 1 LAST COMMENT_BODY TRUE
R 1
J 0
(-6220 2170);
DISPLAY 0.872340 (-6220 2170);
PAINT GREEN (-6220 2170);
DISPLAY INVISIBLE (-6220 2170);
FORCEPROP 2 LAST CDS_LIB mstr_misc
J 0
(-6295 2395);
PAINT ORANGE (-6295 2395);
DISPLAY INVISIBLE (-6295 2395);
FORCEADD INTEL_CORP_BPAGE..1
(-375 -75);
FORCEPROP 1 LAST CDS_CON_LAST_MODIFIED Tue Dec 01 11:52:30 2015
J 0
(-1800 250);
DISPLAY 0.489362 (-1800 250);
PAINT GREEN (-1800 250);
DISPLAY INVISIBLE (-1800 250);
FORCEPROP 1 LAST CUSTOM_TXT_CDS <CURRENT_DESIGN_SHEET> OF <TOTAL_DESIGN_SHEETS>
J 0
(-875 -50);
PAINT GREEN (-875 -50);
FORCEPROP 1 LAST CUSTOM_TXT_CDS <CON_LAST_MODIFIED>
J 0
(-2300 275);
PAINT GREEN (-2300 275);
FORCEPROP 2 LAST CUSTOM_TXT_CDS <XR_PAGE_TITLE>
J 0
(-8265 5175);
DISPLAY 0.638298 (-8265 5175);
PAINT PINK (-8265 5175);
DISPLAY INVISIBLE (-8265 5175);
FORCEPROP 1 LAST SCH_ADDRESS3 Santa Clara, CA 95052-8119
J 0
(-4350 -50);
DISPLAY 0.617021 (-4350 -50);
PAINT GREEN (-4350 -50);
FORCEPROP 1 LAST SCH_ADDRESS2 P.O. BOX 58119
J 0
(-4350 0);
DISPLAY 0.617021 (-4350 0);
PAINT GREEN (-4350 0);
FORCEPROP 1 LAST SCH_TITLE VPP KLM VR
J 0
(-8275 50);
DISPLAY 1.212766 (-8275 50);
PAINT GREEN (-8275 50);
FORCEPROP 1 LAST SCH_ADDRESS1 2200 Mission College Blvd.
J 0
(-4350 50);
DISPLAY 0.617021 (-4350 50);
PAINT GREEN (-4350 50);
FORCEPROP 1 LAST SCH_NUMBER H4694802
J 0
(-1675 75);
DISPLAY 1.212766 (-1675 75);
PAINT YELLOW (-1675 75);
FORCEPROP 1 LAST SCH_DEPT BESD
J 1
(-4825 25);
DISPLAY 1.212766 (-4825 25);
PAINT YELLOW (-4825 25);
FORCEPROP 1 LAST SCH_REV 2.420
J 0
(-625 75);
DISPLAY 0.978723 (-625 75);
PAINT YELLOW (-625 75);
FORCEPROP 2 LAST CDS_LIB mstr_symbols
J 0
(-375 -75);
DISPLAY 0.489362 (-375 -75);
PAINT ORANGE (-375 -75);
DISPLAY INVISIBLE (-375 -75);
FORCEPROP 1 LAST COMMENT_BODY TRUE
J 0
(-363 -63);
DISPLAY 0.212766 (-363 -63);
PAINT GREEN (-363 -63);
DISPLAY INVISIBLE (-363 -63);
FORCEPROP 2 LAST PAGE_BORDER TRUE
J 0
(-8265 5175);
DISPLAY 0.425532 (-8265 5175);
PAINT PINK (-8265 5175);
DISPLAY INVISIBLE (-8265 5175);
FORCEPROP 2 LAST CDS_XR_PAGE_TITLE CR-234 : @BASEBOARD_FAB2_LIB.BASEBOARD_FAB2(SCH_1):PAGE234
J 0
(-8265 5175);
DISPLAY 0.638298 (-8265 5175);
PAINT PINK (-8265 5175);
DISPLAY INVISIBLE (-8265 5175);
WIRE 16 -1 (-7275 3950)(-7275 4050);
WIRE 16 -1 (-3875 625)(-3875 525);
WIRE 16 -1 (-4225 1475)(-4225 1350);
WIRE 16 -1 (-4950 3875)(-4950 4050);
WIRE 16 -1 (-7825 4300)(-7600 4300);
WIRE 16 -1 (-7825 4450)(-7825 4300);
WIRE 16 -1 (-3300 2725)(-3075 2725);
WIRE 16 -1 (-3075 2725)(-3075 2675);
WIRE 16 -1 (-3300 2675)(-3075 2675);
WIRE 16 -1 (-3075 2675)(-3075 2625);
WIRE 16 -1 (-3300 2625)(-3075 2625);
WIRE 16 -1 (-3075 2625)(-3075 2575);
WIRE 16 -1 (-3300 2575)(-3075 2575);
WIRE 16 -1 (-3075 2575)(-3075 2525);
WIRE 16 -1 (-3300 2525)(-3075 2525);
WIRE 16 -1 (-3075 2525)(-3075 2475);
WIRE 16 -1 (-3300 2475)(-3075 2475);
WIRE 16 -1 (-3075 2475)(-3075 2425);
WIRE 16 -1 (-3300 2425)(-3075 2425);
WIRE 16 -1 (-3075 2425)(-3075 2375);
WIRE 16 -1 (-3300 2375)(-3075 2375);
WIRE 16 -1 (-3075 2375)(-3075 2325);
WIRE 16 -1 (-3300 2325)(-3075 2325);
WIRE 16 -1 (-3075 2325)(-3075 2275);
WIRE 16 -1 (-3300 2275)(-3075 2275);
WIRE 16 -1 (-3075 2275)(-3075 2225);
WIRE 16 -1 (-3300 2225)(-3075 2225);
WIRE 16 -1 (-3075 2225)(-3075 2175);
WIRE 16 -1 (-3300 2175)(-3075 2175);
WIRE 16 -1 (-3075 2175)(-3075 2125);
WIRE 16 -1 (-3300 2125)(-3075 2125);
WIRE 16 -1 (-3075 2125)(-3075 2075);
WIRE 16 -1 (-3300 2075)(-3075 2075);
WIRE 16 -1 (-3075 2075)(-3075 2025);
WIRE 16 -1 (-3300 2025)(-3075 2025);
WIRE 16 -1 (-3075 2025)(-3075 1975);
WIRE 16 -1 (-2650 3250)(-2650 3200);
WIRE 16 -1 (-2075 3475)(-2075 3575);
WIRE 16 -1 (-1750 3500)(-1750 3575);
WIRE 16 -1 (-1425 3500)(-1425 3575);
WIRE 16 -1 (-1150 3525)(-1150 3575);
WIRE 16 -1 (-2200 3850)(-2075 3850);
WIRE 16 -1 (-2075 3850)(-1750 3850);
WIRE 16 -1 (-2075 3775)(-2075 3850);
WIRE 16 -1 (-1750 3850)(-1425 3850);
WIRE 16 -1 (-1750 3850)(-1750 3775);
WIRE 16 -1 (-1425 3775)(-1425 3850);
WIRE 16 -1 (-1425 3850)(-1150 3850);
WIRE 16 -1 (-1150 3850)(-850 3850);
WIRE 16 -1 (-1150 3850)(-1150 3775);
WIRE 16 -1 (-800 3850)(-850 3850);
WIRE 16 -1 (-850 3850)(-850 3750);
WIRE 16 -1 (-600 3850)(-800 3850);
WIRE 16 -1 (-800 3925)(-800 3850);
WIRE 16 -1 (-600 3850)(-600 3175);
WIRE 16 -1 (-1350 3175)(-600 3175);
WIRE 16 -1 (-1350 3175)(-1350 3025);
WIRE 16 -1 (-6300 2125)(-6300 2300);
WIRE 16 -1 (-5600 2150)(-5600 2300);
WIRE 16 -1 (-5075 2075)(-5075 2000);
WIRE 16 -1 (-4750 1550)(-4750 1400);
WIRE 16 -1 (-4375 2025)(-4300 2025);
WIRE 16 -1 (-4375 1900)(-4375 2025);
WIRE 16 -1 (-5175 3425)(-5175 3350);
WIRE 16 -1 (-5400 2925)(-4300 2925);
WIRE 16 -1 (-5400 2750)(-5400 2925);
WIRE 16 -1 (-6875 3950)(-6875 4000);
WIRE 16 -1 (-6375 3950)(-6375 4000);
WIRE 16 -1 (-5925 3950)(-5925 4000);
WIRE 16 -1 (-5475 3950)(-5475 4000);
WIRE 16 -1 (-1350 1225)(-1350 1450);
WIRE 16 -1 (-1450 650)(-1250 650);
WIRE 16 -1 (-1450 600)(-1450 650);
WIRE 16 -1 (-900 600)(-900 650);
WIRE 16 -1 (-900 650)(-1050 650);
WIRE 16 -1 (-8175 625)(-8175 475);
WIRE 16 -1 (-8175 475)(-7925 475);
WIRE 16 -1 (-7925 625)(-7925 475);
WIRE 16 -1 (-7650 475)(-7925 475);
WIRE 16 -1 (-7650 625)(-7650 475);
WIRE 16 -1 (-7400 475)(-7650 475);
WIRE 16 -1 (-7400 600)(-7400 475);
WIRE 16 -1 (-7125 475)(-7400 475);
WIRE 16 -1 (-7125 625)(-7125 475);
WIRE 16 -1 (-6825 475)(-7125 475);
WIRE 16 -1 (-6825 625)(-6825 475);
WIRE 16 -1 (-6550 475)(-6825 475);
WIRE 16 -1 (-6550 625)(-6550 475);
WIRE 16 -1 (-6250 475)(-6550 475);
WIRE 16 -1 (-6250 625)(-6250 475);
WIRE 16 -1 (-5950 475)(-6250 475);
WIRE 16 -1 (-5950 625)(-5950 475);
WIRE 16 -1 (-5675 475)(-5950 475);
WIRE 16 -1 (-5675 600)(-5675 475);
WIRE 16 -1 (-5400 475)(-5675 475);
WIRE 16 -1 (-5400 600)(-5400 475);
WIRE 16 -1 (-5225 475)(-5400 475);
WIRE 16 -1 (-5225 475)(-5150 475);
WIRE 16 -1 (-5225 475)(-5225 450);
WIRE 16 -1 (-5150 625)(-5150 475);
WIRE 16 -1 (-5150 825)(-5150 900);
WIRE 16 -1 (-5150 900)(-5400 900);
WIRE 16 -1 (-5400 800)(-5400 900);
WIRE 16 -1 (-5400 900)(-5675 900);
WIRE 16 -1 (-5675 800)(-5675 900);
WIRE 16 -1 (-5675 900)(-5950 900);
WIRE 16 -1 (-5950 825)(-5950 900);
WIRE 16 -1 (-5950 900)(-6250 900);
WIRE 16 -1 (-6250 825)(-6250 900);
WIRE 16 -1 (-6250 900)(-6550 900);
WIRE 16 -1 (-6550 900)(-6550 825);
WIRE 16 -1 (-6550 900)(-6825 900);
WIRE 16 -1 (-6825 825)(-6825 900);
WIRE 16 -1 (-6825 900)(-7125 900);
WIRE 16 -1 (-7125 825)(-7125 900);
WIRE 16 -1 (-7125 900)(-7400 900);
WIRE 16 -1 (-7400 800)(-7400 900);
WIRE 16 -1 (-7400 900)(-7650 900);
WIRE 16 -1 (-7650 825)(-7650 900);
WIRE 16 -1 (-7650 900)(-7925 900);
WIRE 16 -1 (-7925 825)(-7925 900);
WIRE 16 -1 (-8175 900)(-7925 900);
WIRE 16 -1 (-8175 900)(-8175 950);
WIRE 16 -1 (-8175 900)(-8175 825);
WIRE 16 682 (-950 4600)(-2000 4600);
WIRE 16 682 (-950 4050)(-950 4600);
WIRE 16 682 (-2000 4600)(-2000 4050);
WIRE 16 682 (-2000 4050)(-950 4050);
WIRE 16 -1 (-3275 4200)(-3025 4200);
WIRE 16 -1 (-3025 4200)(-3025 3850);
WIRE 16 -1 (-3025 3850)(-2650 3850);
FORCEPROP 2 LAST SIG_NAME VR_PVPP_KLM_PHASE
J 0
(-3010 3860);
DISPLAY 0.617021 (-3010 3860);
PAINT ORANGE (-3010 3860);
FORCEPROP 2 LASTPROP $XRERR UNIQUE?
J 0
(-3250 3860);
DISPLAY 0.638298 (-3250 3860);
PAINT MONO (-3250 3860);
DISPLAY INVISIBLE (-3250 3860);
WIRE 16 -1 (-3025 3475)(-3025 3850);
WIRE 16 -1 (-3025 3425)(-3025 3475);
WIRE 16 -1 (-3300 3475)(-3025 3475);
WIRE 16 -1 (-2400 3850)(-2650 3850);
WIRE 16 -1 (-2650 3800)(-2650 3850);
WIRE 16 -1 (-3025 3375)(-3025 3425);
WIRE 16 -1 (-3300 3425)(-3025 3425);
WIRE 16 -1 (-3025 3325)(-3025 3375);
WIRE 16 -1 (-3300 3375)(-3025 3375);
WIRE 16 -1 (-3025 3275)(-3025 3325);
WIRE 16 -1 (-3300 3325)(-3025 3325);
WIRE 16 -1 (-3025 3225)(-3025 3275);
WIRE 16 -1 (-3300 3275)(-3025 3275);
WIRE 16 -1 (-3025 3175)(-3025 3225);
WIRE 16 -1 (-3300 3225)(-3025 3225);
WIRE 16 -1 (-3025 3125)(-3025 3175);
WIRE 16 -1 (-3300 3175)(-3025 3175);
WIRE 16 -1 (-3025 3025)(-3025 3125);
WIRE 16 -1 (-3300 3125)(-3025 3125);
WIRE 16 -1 (-3300 3025)(-3025 3025);
WIRE 16 -1 (-3475 4200)(-3975 4200);
FORCEPROP 2 LAST SIG_NAME VR_PVPP_KLM_BOOT_R
J 0
(-3955 4210);
DISPLAY 0.617021 (-3955 4210);
PAINT ORANGE (-3955 4210);
FORCEPROP 2 LASTPROP $XRERR UNIQUE?
J 0
(-4195 4210);
DISPLAY 0.638298 (-4195 4210);
PAINT MONO (-4195 4210);
DISPLAY INVISIBLE (-4195 4210);
WIRE 16 2175 (-3175 4375)(-3175 4000);
WIRE 16 2175 (-4400 4375)(-3175 4375);
WIRE 16 2175 (-3175 4000)(-4400 4000);
WIRE 16 2175 (-4400 4000)(-4400 4375);
WIRE 16 2175 (-1425 3125)(-775 3125);
WIRE 16 2175 (-1425 1325)(-1425 3125);
WIRE 16 2175 (-775 3125)(-775 1325);
WIRE 16 2175 (-1425 1325)(-775 1325);
WIRE 16 -1 (-1025 2725)(-1025 2800);
WIRE 16 -1 (-1025 2800)(-1350 2800);
WIRE 16 -1 (-1350 2800)(-1350 2825);
WIRE 16 -1 (-1350 2275)(-1350 2800);
FORCEPROP 0 LAST SIG_NAME VSENSE_PVPP_KLM
R 1
J 0
(-1360 2310);
DISPLAY 0.617021 (-1360 2310);
PAINT ORANGE (-1360 2310);
FORCEPROP 2 LASTPROP $XRERR UNIQUE?
J 0
(-1600 2310);
DISPLAY 0.638298 (-1600 2310);
PAINT MONO (-1600 2310);
DISPLAY INVISIBLE (-1600 2310);
WIRE 16 -1 (-1025 2175)(-1025 2525);
FORCEPROP 0 LAST SIG_NAME VR_COMP_PVPP_KLM
R 1
J 0
(-1035 2160);
DISPLAY 0.617021 (-1035 2160);
PAINT ORANGE (-1035 2160);
FORCEPROP 2 LASTPROP $XRERR UNIQUE?
J 0
(-1275 2160);
DISPLAY 0.638298 (-1275 2160);
PAINT MONO (-1275 2160);
DISPLAY INVISIBLE (-1275 2160);
WIRE 16 -1 (-1975 2450)(-1975 2825);
WIRE 16 -1 (-1975 2450)(-2050 2450);
WIRE 16 -1 (-1975 2825)(-1975 2925);
WIRE 16 -1 (-2325 2825)(-1975 2825);
WIRE 16 -1 (-1875 2925)(-1975 2925);
WIRE 16 -1 (-3300 2925)(-1975 2925);
WIRE 16 -1 (-1875 1725)(-1875 2925);
WIRE 16 -1 (-1875 1725)(-1350 1725);
FORCEPROP 0 LAST SIG_NAME VR_FB_PVPP_KLM
J 0
(-1835 1735);
DISPLAY 0.617021 (-1835 1735);
PAINT ORANGE (-1835 1735);
FORCEPROP 2 LASTPROP $XRERR UNIQUE?
J 0
(-2075 1735);
DISPLAY 0.638298 (-2075 1735);
PAINT MONO (-2075 1735);
DISPLAY INVISIBLE (-2075 1735);
WIRE 16 -1 (-1350 1825)(-1350 1725);
WIRE 16 -1 (-1350 1725)(-1350 1650);
WIRE 16 -1 (-1350 2075)(-1350 1825);
WIRE 16 -1 (-1025 1825)(-1350 1825);
WIRE 16 -1 (-1025 1975)(-1025 1825);
WIRE 16 -1 (-2650 3450)(-2650 3600);
FORCEPROP 2 LAST SIG_NAME VR_PVPP_KLM_SNUB
J 0
(-2635 3510);
DISPLAY 0.617021 (-2635 3510);
PAINT ORANGE (-2635 3510);
FORCEPROP 2 LASTPROP $XRERR UNIQUE?
J 0
(-2875 3510);
DISPLAY 0.638298 (-2875 3510);
PAINT MONO (-2875 3510);
DISPLAY INVISIBLE (-2875 3510);
WIRE 16 -1 (-3000 2825)(-2525 2825);
WIRE 16 -1 (-3000 2450)(-3000 2825);
FORCEPROP 0 LAST SIG_NAME VR_COMP_PVPP_KLM_3
J 0
(-3010 2835);
DISPLAY 0.617021 (-3010 2835);
PAINT ORANGE (-3010 2835);
FORCEPROP 2 LASTPROP $XRERR UNIQUE?
J 0
(-3250 2835);
DISPLAY 0.638298 (-3250 2835);
PAINT MONO (-3250 2835);
DISPLAY INVISIBLE (-3250 2835);
WIRE 16 -1 (-3300 2825)(-3000 2825);
WIRE 16 -1 (-2950 2450)(-3000 2450);
WIRE 16 -1 (-2250 2450)(-2750 2450);
FORCEPROP 0 LAST SIG_NAME VR_COMP_RC_PVPP_KLM
J 0
(-2735 2460);
DISPLAY 0.617021 (-2735 2460);
PAINT ORANGE (-2735 2460);
FORCEPROP 2 LASTPROP $XRERR UNIQUE?
J 0
(-2975 2460);
DISPLAY 0.638298 (-2975 2460);
PAINT MONO (-2975 2460);
DISPLAY INVISIBLE (-2975 2460);
WIRE 16 -1 (-3250 3900)(-3250 3575);
WIRE 16 -1 (-4300 3900)(-3250 3900);
WIRE 16 -1 (-3250 3575)(-3300 3575);
WIRE 16 -1 (-4300 4200)(-4300 3900);
FORCEPROP 2 LAST SIG_NAME VR_PVPP_KLM_BOOT
J 0
(-4210 3935);
DISPLAY 0.617021 (-4210 3935);
PAINT ORANGE (-4210 3935);
FORCEPROP 2 LASTPROP $XRERR UNIQUE?
J 0
(-4450 3935);
DISPLAY 0.638298 (-4450 3935);
PAINT MONO (-4450 3935);
DISPLAY INVISIBLE (-4450 3935);
WIRE 16 -1 (-4175 4200)(-4300 4200);
WIRE 16 -1 (-2525 975)(-3250 975);
FORCEPROP 2 LAST SIG_NAME PWRGD_PVPP_KLM
J 0
(-2960 985);
DISPLAY 0.617021 (-2960 985);
PAINT ORANGE (-2960 985);
WIRE 16 -1 (-3875 825)(-3875 975);
WIRE 16 -1 (-3450 975)(-3875 975);
FORCEPROP 2 LAST SIG_NAME PWRGD_PVPP_KLM_R
J 0
(-3985 985);
DISPLAY 0.617021 (-3985 985);
PAINT ORANGE (-3985 985);
FORCEPROP 2 LASTPROP $XRERR UNIQUE?
J 0
(-4225 985);
DISPLAY 0.638298 (-4225 985);
PAINT MONO (-4225 985);
DISPLAY INVISIBLE (-4225 985);
WIRE 16 -1 (-3875 975)(-4225 975);
WIRE 16 -1 (-4225 1150)(-4225 975);
WIRE 16 -1 (-4225 975)(-4550 975);
WIRE 16 -1 (-4550 975)(-4550 2525);
WIRE 16 -1 (-4300 2525)(-4550 2525);
WIRE 16 -1 (-7275 4250)(-7275 4300);
WIRE 16 -1 (-6875 4300)(-7275 4300);
WIRE 16 -1 (-7400 4300)(-7275 4300);
WIRE 16 -1 (-6375 4300)(-6875 4300);
WIRE 16 -1 (-6875 4200)(-6875 4300);
WIRE 16 -1 (-5925 4300)(-6375 4300);
WIRE 16 -1 (-6375 4200)(-6375 4300);
WIRE 16 -1 (-5475 4300)(-5925 4300);
FORCEPROP 0 LAST SIG_NAME VR_FET_SW_P12V_STBY_PVPP_KLM
J 0
(-5910 4310);
DISPLAY 0.617021 (-5910 4310);
PAINT ORANGE (-5910 4310);
FORCEPROP 2 LASTPROP $XRERR UNIQUE?
J 0
(-6150 4310);
DISPLAY 0.638298 (-6150 4310);
PAINT MONO (-6150 4310);
DISPLAY INVISIBLE (-6150 4310);
WIRE 16 -1 (-5925 4200)(-5925 4300);
WIRE 16 -1 (-4950 4300)(-5475 4300);
WIRE 16 -1 (-5475 4200)(-5475 4300);
WIRE 16 -1 (-4950 4300)(-4725 4300);
WIRE 16 -1 (-4950 4250)(-4950 4300);
WIRE 16 -1 (-4725 4300)(-4725 3750);
WIRE 16 -1 (-4725 3750)(-4725 3575);
WIRE 16 -1 (-5175 3750)(-4725 3750);
WIRE 16 -1 (-5175 3625)(-5175 3750);
WIRE 16 -1 (-4300 3575)(-4725 3575);
WIRE 16 -1 (-4725 3575)(-4725 3475);
WIRE 16 -1 (-4725 3475)(-4300 3475);
WIRE 16 -1 (-4725 3425)(-4725 3475);
WIRE 16 -1 (-4300 3425)(-4725 3425);
WIRE 16 -1 (-4725 3375)(-4725 3425);
WIRE 16 -1 (-4300 3375)(-4725 3375);
WIRE 16 -1 (-4725 3325)(-4725 3375);
WIRE 16 -1 (-4300 3325)(-4725 3325);
WIRE 16 -1 (-4725 3275)(-4725 3325);
WIRE 16 -1 (-4300 3275)(-4725 3275);
WIRE 16 -1 (-4725 3225)(-4725 3275);
WIRE 16 -1 (-4300 3225)(-4725 3225);
WIRE 16 -1 (-4725 3175)(-4725 3225);
WIRE 16 -1 (-4300 3175)(-4725 3175);
WIRE 16 -1 (-4725 3125)(-4725 3175);
WIRE 16 -1 (-4300 3125)(-4725 3125);
WIRE 16 2175 (-7350 4350)(-5025 4350);
WIRE 16 2175 (-7350 3850)(-7350 4350);
WIRE 16 2175 (-5025 4350)(-5025 3850);
WIRE 16 2175 (-5025 3850)(-7350 3850);
WIRE 16 -1 (-4750 2625)(-4300 2625);
WIRE 16 -1 (-4750 1750)(-4750 2625);
FORCEPROP 2 LAST SIG_NAME VR_PVPP_KLM_ISET
R 1
J 0
(-4760 2110);
DISPLAY 0.617021 (-4760 2110);
PAINT ORANGE (-4760 2110);
FORCEPROP 2 LASTPROP $XRERR UNIQUE?
J 0
(-5000 2110);
DISPLAY 0.638298 (-5000 2110);
PAINT MONO (-5000 2110);
DISPLAY INVISIBLE (-5000 2110);
WIRE 16 -1 (-4300 2725)(-5075 2725);
WIRE 16 -1 (-5075 2725)(-5075 2275);
FORCEPROP 2 LAST SIG_NAME VR_PVPP_KLM_SS
R 1
J 0
(-5085 2285);
DISPLAY 0.617021 (-5085 2285);
PAINT ORANGE (-5085 2285);
FORCEPROP 2 LASTPROP $XRERR UNIQUE?
J 0
(-5325 2285);
DISPLAY 0.638298 (-5325 2285);
PAINT MONO (-5325 2285);
DISPLAY INVISIBLE (-5325 2285);
WIRE 16 -1 (-5600 3025)(-4300 3025);
FORCEPROP 0 LAST SIG_NAME VR_VB_PVPP_KLM
J 0
(-5310 3035);
DISPLAY 0.617021 (-5310 3035);
PAINT ORANGE (-5310 3035);
FORCEPROP 2 LASTPROP $XRERR UNIQUE?
J 0
(-5550 3035);
DISPLAY 0.638298 (-5550 3035);
PAINT MONO (-5550 3035);
DISPLAY INVISIBLE (-5550 3035);
WIRE 16 -1 (-5600 2500)(-5600 3025);
WIRE 16 -1 (-4300 2825)(-5825 2825);
FORCEPROP 2 LAST SIG_NAME FM_PVPP_PVDDQ_CPU1_EN_KLM
J 0
(-5276 2850);
DISPLAY 0.617021 (-5276 2850);
PAINT ORANGE (-5276 2850);
FORCEPROP 2 LASTPROP $XRERR UNIQUE?
J 0
(-5516 2850);
DISPLAY 0.638298 (-5516 2850);
PAINT MONO (-5516 2850);
DISPLAY INVISIBLE (-5516 2850);
WIRE 16 2175 (-4875 1150)(-4875 350);
WIRE 16 2175 (-8300 1150)(-4875 1150);
WIRE 16 2175 (-4875 350)(-8300 350);
WIRE 16 2175 (-8300 1150)(-8300 350);
WIRE 16 -1 (-6025 2825)(-6300 2825);
WIRE 16 -1 (-6300 2500)(-6300 2825);
WIRE 16 -1 (-6300 2825)(-7600 2825);
FORCEPROP 2 LAST SIG_NAME FM_PVPP_CPU1_EN
J 0
(-7601 2850);
DISPLAY 0.617021 (-7601 2850);
PAINT ORANGE (-7601 2850);
DOT 1 (-7925 475);
DOT 1 (-8175 900);
DOT 1 (-7925 900);
DOT 1 (-7650 475);
DOT 1 (-7400 475);
DOT 1 (-7650 900);
DOT 1 (-7400 900);
DOT 1 (-7125 475);
DOT 1 (-6825 475);
DOT 1 (-7125 900);
DOT 1 (-6825 900);
DOT 1 (-6550 475);
DOT 1 (-6250 475);
DOT 1 (-6550 900);
DOT 1 (-6250 900);
DOT 1 (-6300 2825);
DOT 1 (-5950 475);
DOT 1 (-5675 475);
DOT 1 (-5950 900);
DOT 1 (-5675 900);
DOT 1 (-5400 475);
DOT 1 (-5225 475);
DOT 1 (-5400 900);
DOT 1 (-4225 975);
DOT 1 (-4725 3175);
DOT 1 (-4725 3225);
DOT 1 (-4725 3275);
DOT 1 (-4725 3325);
DOT 1 (-4725 3375);
DOT 1 (-4725 3425);
DOT 1 (-4725 3475);
DOT 1 (-4725 3575);
DOT 1 (-4725 3750);
DOT 1 (-7275 4300);
DOT 1 (-6875 4300);
DOT 1 (-6375 4300);
DOT 1 (-5925 4300);
DOT 1 (-5475 4300);
DOT 1 (-4950 4300);
DOT 1 (-3875 975);
DOT 1 (-3075 2025);
DOT 1 (-3075 2125);
DOT 1 (-3075 2175);
DOT 1 (-3075 2075);
DOT 1 (-3075 2225);
DOT 1 (-3075 2275);
DOT 1 (-3075 2375);
DOT 1 (-3075 2425);
DOT 1 (-3075 2325);
DOT 1 (-3075 2525);
DOT 1 (-3075 2475);
DOT 1 (-3075 2675);
DOT 1 (-3075 2625);
DOT 1 (-3075 2575);
DOT 1 (-3000 2825);
DOT 1 (-3025 3175);
DOT 1 (-3025 3125);
DOT 1 (-3025 3225);
DOT 1 (-3025 3275);
DOT 1 (-3025 3325);
DOT 1 (-3025 3425);
DOT 1 (-3025 3375);
DOT 1 (-3025 3475);
DOT 1 (-3025 3850);
DOT 1 (-2650 3850);
DOT 1 (-2075 3850);
DOT 1 (-1350 1725);
DOT 1 (-1350 1825);
DOT 1 (-1975 2825);
DOT 1 (-1975 2925);
DOT 1 (-1350 2800);
DOT 1 (-1750 3850);
DOT 1 (-1425 3850);
DOT 1 (-1150 3850);
DOT 1 (-850 3850);
DOT 1 (-800 3850);
FORCENOTE
CAPS TO BE PLACED BETWEEN DIMMS
(-7820 1055) 0;
DISPLAY LEFT (-7820 1055);
DISPLAY 1.021277 (-7820 1055);
PAINT PURPLE (-7820 1055);
FORCENOTE
ROOM = PVPP_KLM_VR
(-7475 75) 0;
DISPLAY LEFT (-7475 75);
DISPLAY 0.787234 (-7475 75);
PAINT PURPLE (-7475 75);
FORCENOTE
BOM_COST: PVPP_KLM_VR
(-7475 25) 0;
DISPLAY LEFT (-7475 25);
DISPLAY 0.787234 (-7475 25);
PAINT PURPLE (-7475 25);
FORCENOTE
25A OC
(-5195 1630) 0;
DISPLAY LEFT (-5195 1630);
PAINT PURPLE (-5195 1630);
FORCENOTE
(0.4V/MS)
(-5345 2105) 0;
DISPLAY LEFT (-5345 2105);
PAINT PURPLE (-5345 2105);
FORCENOTE
6.25MS
(-5320 2180) 0;
DISPLAY LEFT (-5320 2180);
PAINT PURPLE (-5320 2180);
FORCENOTE
PLACE ON
(-4100 4425) 0;
DISPLAY LEFT (-4100 4425);
DISPLAY 1.042553 (-4100 4425);
PAINT PURPLE (-4100 4425);
FORCENOTE
SPOF
(-4400 4425) 0;
DISPLAY LEFT (-4400 4425);
DISPLAY 1.659574 (-4400 4425);
PAINT PURPLE (-4400 4425);
FORCENOTE
COMPENSATION TYPE III
(-2975 2150) 0;
DISPLAY LEFT (-2975 2150);
DISPLAY 1.042553 (-2975 2150);
PAINT PURPLE (-2975 2150);
FORCENOTE
POINT ONLY TOP TO L2
(-1500 800) 0;
DISPLAY LEFT (-1500 800);
DISPLAY 1.042553 (-1500 800);
PAINT PURPLE (-1500 800);
FORCENOTE
CONNECT AT SINGLE
(-1450 850) 0;
DISPLAY LEFT (-1450 850);
DISPLAY 1.042553 (-1450 850);
PAINT PURPLE (-1450 850);
FORCENOTE
SPOF
(-1205 2975) 0;
DISPLAY LEFT (-1205 2975);
DISPLAY 2.340426 (-1205 2975);
PAINT PURPLE (-1205 2975);
FORCENOTE
TOP LAYER
(-3725 4425) 0;
DISPLAY LEFT (-3725 4425);
DISPLAY 1.042553 (-3725 4425);
PAINT PURPLE (-3725 4425);
FORCENOTE
SW FREQ =  500KHZ
(-1975 4125) 0;
DISPLAY LEFT (-1975 4125);
DISPLAY 1.021277 (-1975 4125);
PAINT PURPLE (-1975 4125);
FORCENOTE
IOUT DI/DT = 25A/US
(-1975 4175) 0;
DISPLAY LEFT (-1975 4175);
DISPLAY 1.021277 (-1975 4175);
PAINT PURPLE (-1975 4175);
FORCENOTE
IOUT STEP = 3A
(-1975 4225) 0;
DISPLAY LEFT (-1975 4225);
DISPLAY 1.021277 (-1975 4225);
PAINT PURPLE (-1975 4225);
FORCENOTE
VOUT = 2.5V
(-1975 4525) 0;
DISPLAY LEFT (-1975 4525);
DISPLAY 1.021277 (-1975 4525);
PAINT PURPLE (-1975 4525);
FORCENOTE
DC TOL = +/-1.5%
(-1975 4425) 0;
DISPLAY LEFT (-1975 4425);
DISPLAY 1.021277 (-1975 4425);
PAINT PURPLE (-1975 4425);
FORCENOTE
IOUT TDC = 8A
(-1975 4325) 0;
DISPLAY LEFT (-1975 4325);
DISPLAY 1.021277 (-1975 4325);
PAINT PURPLE (-1975 4325);
FORCENOTE
IOUT PK = 15A
(-1975 4275) 0;
DISPLAY LEFT (-1975 4275);
DISPLAY 1.021277 (-1975 4275);
PAINT PURPLE (-1975 4275);
FORCENOTE
AC & RIPPLE TOL = +3.5%, -7.3%
(-1975 4375) 0;
DISPLAY LEFT (-1975 4375);
DISPLAY 1.021277 (-1975 4375);
PAINT PURPLE (-1975 4375);
FORCENOTE
RIPPLE GUIDELINE = +/- 1.0%
(-1975 4475) 0;
DISPLAY LEFT (-1975 4475);
DISPLAY 1.021277 (-1975 4475);
PAINT PURPLE (-1975 4475);
QUIT
